FILE_TYPE = MACRO_DRAWING;
SET COLOR_WIRE YELLOW;
SET COLOR_PROP MONO;
SET COLOR_DOT WHITE;
SET COLOR_ARC YELLOW;
SET COLOR_BODY GREEN;
SET COLOR_NOTE MONO;
SET PROP_DISPLAY VALUE;
SET PAGE_NUMBER P118;
FORCEADD OFFPAGE..1
(-5775 3925);
FORCEPROP 2 LAST $XR3 190 
J 0
(-6356 3925);
DISPLAY 0.638298 (-6356 3925);
PAINT MONO (-6356 3925);
FORCEPROP 2 LAST $XR2 146 
J 0
(-6236 3925);
DISPLAY 0.638298 (-6236 3925);
PAINT MONO (-6236 3925);
FORCEPROP 2 LAST $XR1 112 
J 0
(-6116 3925);
DISPLAY 0.638298 (-6116 3925);
PAINT MONO (-6116 3925);
FORCEPROP 2 LAST $XR0 55 
J 0
(-5996 3925);
DISPLAY 0.638298 (-5996 3925);
PAINT MONO (-5996 3925);
FORCEPROP 2 LAST PATH I115
J 0
(-5725 4000);
DISPLAY 1.021277 (-5725 4000);
PAINT ORANGE (-5725 4000);
DISPLAY INVISIBLE (-5725 4000);
FORCEPROP 2 LAST CDS_LIB mstr_standard
J 0
(-5775 3925);
PAINT MONO (-5775 3925);
DISPLAY INVISIBLE (-5775 3925);
FORCEPROP 1 LAST OFFPAGE TRUE
J 0
(-5450 3800);
PAINT GREEN (-5450 3800);
DISPLAY INVISIBLE (-5450 3800);
FORCEPROP 1 LAST COMMENT_BODY TRUE
J 0
(-5650 3825);
DISPLAY 1.404255 (-5650 3825);
PAINT PEACH (-5650 3825);
DISPLAY INVISIBLE (-5650 3825);
FORCEADD P1V05_PCH_STBY_KR_PLL..1
(-1000 2025);
FORCEPROP 3 LASTPIN (-1000 1975) SIG_NAME P1V05_PCH_STBY_KR_PLL\g
J 0
(-990 1985);
DISPLAY 0.659574 (-990 1985);
PAINT MONO (-990 1985);
DISPLAY INVISIBLE (-990 1985);
FORCEPROP 2 LAST BOM_COST SB
J 0
(-1000 2175);
PAINT MONO (-1000 2175);
DISPLAY INVISIBLE (-1000 2175);
FORCEPROP 1 LAST PATH I117
J 0
(-950 2050);
DISPLAY 0.872340 (-950 2050);
PAINT AQUA (-950 2050);
DISPLAY INVISIBLE (-950 2050);
FORCEPROP 2 LAST ROOM SB_DECOUPLING
J 0
(-1000 2125);
DISPLAY 1.361702 (-1000 2125);
PAINT WHITE (-1000 2125);
DISPLAY INVISIBLE (-1000 2125);
FORCEPROP 2 LAST CDS_LIB mstr_symbols
J 0
(-1000 2025);
PAINT ORANGE (-1000 2025);
DISPLAY INVISIBLE (-1000 2025);
FORCEPROP 1 LAST VOLTAGE 1.05V
J 0
(-1045 1982);
DISPLAY 0.340426 (-1045 1982);
PAINT SKYBLUE (-1045 1982);
DISPLAY INVISIBLE (-1045 1982);
FORCEPROP 1 LAST BODY_TYPE PLUMBING
J 0
(-1045 1982);
DISPLAY 0.340426 (-1045 1982);
PAINT GREEN (-1045 1982);
DISPLAY INVISIBLE (-1045 1982);
FORCEPROP 1 LAST HDL_POWER P1V05_PCH_STBY_KR_PLL
J 1
(-1000 2075);
DISPLAY 0.872340 (-1000 2075);
PAINT GREEN (-1000 2075);
DISPLAY INVISIBLE (-1000 2075);
FORCEADD P1V05_PCH_STBY_KR_PLL..1
(-7225 2400);
FORCEPROP 3 LASTPIN (-7225 2350) SIG_NAME P1V05_PCH_STBY_KR_PLL\g
J 0
(-7215 2360);
DISPLAY 0.659574 (-7215 2360);
PAINT MONO (-7215 2360);
DISPLAY INVISIBLE (-7215 2360);
FORCEPROP 2 LAST BOM_COST SB
J 0
(-7225 2550);
PAINT MONO (-7225 2550);
DISPLAY INVISIBLE (-7225 2550);
FORCEPROP 1 LAST VOLTAGE 1.05V
J 0
(-7270 2357);
DISPLAY 0.340426 (-7270 2357);
PAINT SKYBLUE (-7270 2357);
DISPLAY INVISIBLE (-7270 2357);
FORCEPROP 2 LAST CDS_LIB mstr_symbols
J 0
(-7225 2400);
PAINT ORANGE (-7225 2400);
DISPLAY INVISIBLE (-7225 2400);
FORCEPROP 1 LAST PATH I118
J 0
(-7175 2425);
DISPLAY 0.872340 (-7175 2425);
PAINT AQUA (-7175 2425);
DISPLAY INVISIBLE (-7175 2425);
FORCEPROP 2 LAST ROOM SB_DECOUPLING
J 0
(-7225 2500);
DISPLAY 1.361702 (-7225 2500);
PAINT WHITE (-7225 2500);
DISPLAY INVISIBLE (-7225 2500);
FORCEPROP 1 LAST BODY_TYPE PLUMBING
J 0
(-7270 2357);
DISPLAY 0.340426 (-7270 2357);
PAINT GREEN (-7270 2357);
DISPLAY INVISIBLE (-7270 2357);
FORCEPROP 1 LAST HDL_POWER P1V05_PCH_STBY_KR_PLL
J 1
(-7225 2450);
DISPLAY 0.872340 (-7225 2450);
PAINT GREEN (-7225 2450);
DISPLAY INVISIBLE (-7225 2450);
FORCEADD OFFPAGE..5
(-7375 4225);
FORCEPROP 2 LAST $XR1 169 
J 0
(-7780 4225);
DISPLAY 0.638298 (-7780 4225);
PAINT MONO (-7780 4225);
FORCEPROP 2 LAST $XR0 145 
J 0
(-7660 4225);
DISPLAY 0.638298 (-7660 4225);
PAINT MONO (-7660 4225);
FORCEPROP 2 LAST PATH I119
J 0
(-7325 4300);
DISPLAY 1.021277 (-7325 4300);
PAINT ORANGE (-7325 4300);
DISPLAY INVISIBLE (-7325 4300);
FORCEPROP 2 LAST CDS_LIB mstr_standard
J 0
(-7375 4225);
PAINT MONO (-7375 4225);
DISPLAY INVISIBLE (-7375 4225);
FORCEPROP 1 LAST OFFPAGE TRUE
J 0
(-7050 4100);
PAINT GREEN (-7050 4100);
DISPLAY INVISIBLE (-7050 4100);
FORCEPROP 1 LAST COMMENT_BODY TRUE
J 0
(-7275 4150);
DISPLAY 1.404255 (-7275 4150);
PAINT PEACH (-7275 4150);
DISPLAY INVISIBLE (-7275 4150);
FORCEADD RES..1
(-1675 900);
FORCEPROP 1 LASTPIN (-1575 900) $PN 2
J 0
(-1613 912);
DISPLAY 0.617021 (-1613 912);
PAINT ORANGE (-1613 912);
FORCEPROP 1 LAST VALUE 0.0
J 2
(-1725 850);
DISPLAY 0.617021 (-1725 850);
PAINT SKYBLUE (-1725 850);
FORCEPROP 1 LASTPIN (-1775 900) $PN 1
J 0
(-1763 912);
DISPLAY 0.617021 (-1763 912);
PAINT ORANGE (-1763 912);
FORCEPROP 1 LAST LOCATION R8C24
J 0
(-1725 950);
DISPLAY 0.617021 (-1725 950);
PAINT AQUA (-1725 950);
FORCEPROP 1 LAST TOLERANCE 5%
J 0
(-1675 850);
DISPLAY 0.617021 (-1675 850);
PAINT SKYBLUE (-1675 850);
FORCEPROP 1 LAST PACK_TYPE 0402
J 0
(-1600 850);
DISPLAY 0.617021 (-1600 850);
PAINT SKYBLUE (-1600 850);
FORCEPROP 1 LAST MATERIAL CHIP
J 0
(-1675 800);
DISPLAY 0.617021 (-1675 800);
PAINT SKYBLUE (-1675 800);
FORCEPROP 1 LAST PART_NUMBER G21497-005
J 0
(-1575 800);
DISPLAY 0.617021 (-1575 800);
PAINT BLUE (-1575 800);
FORCEPROP 1 LAST WATTAGE 1/16W
J 2
(-1675 800);
DISPLAY 0.617021 (-1675 800);
PAINT SKYBLUE (-1675 800);
FORCEPROP 2 LAST SEC 1
J 0
(-1725 1100);
DISPLAY 0.680851 (-1725 1100);
PAINT MONO (-1725 1100);
DISPLAY INVISIBLE (-1725 1100);
FORCEPROP 2 LAST SEC_TYPE 0402
J 0
(-1725 1100);
DISPLAY 1.021277 (-1725 1100);
PAINT ORANGE (-1725 1100);
DISPLAY INVISIBLE (-1725 1100);
FORCEPROP 2 LAST BOM_COST SB
J 0
(-1725 1050);
DISPLAY 1.021277 (-1725 1050);
PAINT ORANGE (-1725 1050);
DISPLAY INVISIBLE (-1725 1050);
FORCEPROP 1 LAST PATH I120
J 0
(-1725 1050);
DISPLAY 0.978723 (-1725 1050);
PAINT WHITE (-1725 1050);
DISPLAY INVISIBLE (-1725 1050);
FORCEPROP 2 LAST ROOM SB
J 0
(-1725 1000);
DISPLAY 1.021277 (-1725 1000);
PAINT ORANGE (-1725 1000);
DISPLAY INVISIBLE (-1725 1000);
FORCEPROP 2 LAST CDS_LOCATION R8C24
J 0
(-1725 950);
DISPLAY 0.617021 (-1725 950);
PAINT AQUA (-1725 950);
DISPLAY INVISIBLE (-1725 950);
FORCEPROP 2 LAST CDS_LIB mstr_discrete
J 0
(-1675 900);
PAINT MONO (-1675 900);
DISPLAY INVISIBLE (-1675 900);
FORCEADD OFFPAGE..2
(-825 900);
FORCEPROP 2 LAST $XR0 139 
J 0
(-636 900);
DISPLAY 0.638298 (-636 900);
PAINT MONO (-636 900);
FORCEPROP 2 LAST PATH I122
J 0
(-650 975);
DISPLAY 1.021277 (-650 975);
PAINT ORANGE (-650 975);
DISPLAY INVISIBLE (-650 975);
FORCEPROP 2 LAST CDS_LIB mstr_standard
J 0
(-825 900);
PAINT MONO (-825 900);
DISPLAY INVISIBLE (-825 900);
FORCEPROP 1 LAST OFFPAGE TRUE
J 0
(-500 775);
DISPLAY 1.170213 (-500 775);
PAINT GREEN (-500 775);
DISPLAY INVISIBLE (-500 775);
FORCEPROP 1 LAST COMMENT_BODY TRUE
J 0
(-870 805);
DISPLAY 1.170213 (-870 805);
PAINT PEACH (-870 805);
DISPLAY INVISIBLE (-870 805);
FORCEADD OFFPAGE..2
(-825 675);
FORCEPROP 2 LAST $XR0 120 
J 0
(-636 675);
DISPLAY 0.638298 (-636 675);
PAINT MONO (-636 675);
FORCEPROP 2 LAST PATH I123
J 0
(-650 750);
DISPLAY 1.021277 (-650 750);
PAINT ORANGE (-650 750);
DISPLAY INVISIBLE (-650 750);
FORCEPROP 2 LAST CDS_LIB mstr_standard
J 0
(-825 675);
PAINT MONO (-825 675);
DISPLAY INVISIBLE (-825 675);
FORCEPROP 1 LAST OFFPAGE TRUE
J 0
(-500 550);
DISPLAY 1.170213 (-500 550);
PAINT GREEN (-500 550);
DISPLAY INVISIBLE (-500 550);
FORCEPROP 1 LAST COMMENT_BODY TRUE
J 0
(-870 580);
DISPLAY 1.170213 (-870 580);
PAINT PEACH (-870 580);
DISPLAY INVISIBLE (-870 580);
FORCEADD OFFPAGE..1
(-2900 900);
FORCEPROP 2 LAST $XR0 118 
J 0
(-3152 900);
DISPLAY 0.638298 (-3152 900);
PAINT MONO (-3152 900);
FORCEPROP 2 LAST CDS_LIB mstr_standard
J 0
(-2900 900);
PAINT MONO (-2900 900);
DISPLAY INVISIBLE (-2900 900);
FORCEPROP 2 LAST PATH I124
J 0
(-2850 975);
DISPLAY 1.021277 (-2850 975);
PAINT ORANGE (-2850 975);
DISPLAY INVISIBLE (-2850 975);
FORCEPROP 1 LAST OFFPAGE TRUE
J 0
(-2575 775);
DISPLAY 0.872340 (-2575 775);
PAINT GREEN (-2575 775);
DISPLAY INVISIBLE (-2575 775);
FORCEPROP 1 LAST COMMENT_BODY TRUE
J 0
(-2775 800);
DISPLAY 0.872340 (-2775 800);
PAINT GREEN (-2775 800);
DISPLAY INVISIBLE (-2775 800);
FORCEADD RES..1
(-1675 675);
FORCEPROP 1 LAST MATERIAL EMPTY
J 0
(-1675 525);
DISPLAY 0.617021 (-1675 525);
PAINT RED (-1675 525);
FORCEPROP 1 LAST PART_NUMBER G21497-005
J 0
(-1550 525);
DISPLAY 0.617021 (-1550 525);
PAINT BLUE (-1550 525);
FORCEPROP 1 LAST PACK_TYPE 0402
J 0
(-1575 575);
DISPLAY 0.617021 (-1575 575);
PAINT SKYBLUE (-1575 575);
FORCEPROP 1 LASTPIN (-1775 675) $PN 1
J 0
(-1763 687);
DISPLAY 0.617021 (-1763 687);
PAINT ORANGE (-1763 687);
FORCEPROP 1 LAST LOCATION R8C23
J 0
(-1725 725);
DISPLAY 0.617021 (-1725 725);
PAINT AQUA (-1725 725);
FORCEPROP 1 LASTPIN (-1575 675) $PN 2
J 0
(-1613 687);
DISPLAY 0.617021 (-1613 687);
PAINT ORANGE (-1613 687);
FORCEPROP 1 LAST TOLERANCE 5%
J 0
(-1675 575);
DISPLAY 0.617021 (-1675 575);
PAINT SKYBLUE (-1675 575);
FORCEPROP 1 LAST VALUE 0.0
J 2
(-1700 575);
DISPLAY 0.617021 (-1700 575);
PAINT SKYBLUE (-1700 575);
FORCEPROP 1 LAST WATTAGE 1/16W
J 2
(-1700 525);
DISPLAY 0.617021 (-1700 525);
PAINT SKYBLUE (-1700 525);
FORCEPROP 2 LAST ROOM SB
J 0
(-1725 775);
DISPLAY 1.021277 (-1725 775);
PAINT ORANGE (-1725 775);
DISPLAY INVISIBLE (-1725 775);
FORCEPROP 1 LAST PATH I125
J 0
(-1725 825);
DISPLAY 0.978723 (-1725 825);
PAINT WHITE (-1725 825);
DISPLAY INVISIBLE (-1725 825);
FORCEPROP 2 LAST BOM_COST SB
J 0
(-1725 825);
DISPLAY 1.021277 (-1725 825);
PAINT ORANGE (-1725 825);
DISPLAY INVISIBLE (-1725 825);
FORCEPROP 2 LAST SEC_TYPE 0402
J 0
(-1725 875);
DISPLAY 1.021277 (-1725 875);
PAINT ORANGE (-1725 875);
DISPLAY INVISIBLE (-1725 875);
FORCEPROP 2 LAST SEC 1
J 0
(-1725 875);
DISPLAY 0.680851 (-1725 875);
PAINT MONO (-1725 875);
DISPLAY INVISIBLE (-1725 875);
FORCEPROP 2 LAST CDS_LOCATION R8C23
J 0
(-1725 725);
DISPLAY 0.617021 (-1725 725);
PAINT AQUA (-1725 725);
DISPLAY INVISIBLE (-1725 725);
FORCEPROP 2 LAST CDS_LIB mstr_discrete
J 0
(-1675 675);
PAINT ORANGE (-1675 675);
DISPLAY INVISIBLE (-1675 675);
FORCEADD OFFPAGE..5
(-5775 4325);
FORCEPROP 2 LAST $XR2 190 
J 0
(-6300 4325);
DISPLAY 0.638298 (-6300 4325);
PAINT MONO (-6300 4325);
FORCEPROP 2 LAST $XR1 157 
J 0
(-6180 4325);
DISPLAY 0.638298 (-6180 4325);
PAINT MONO (-6180 4325);
FORCEPROP 2 LAST $XR0 147 
J 0
(-6060 4325);
DISPLAY 0.638298 (-6060 4325);
PAINT MONO (-6060 4325);
FORCEPROP 2 LAST PATH I126
J 0
(-5725 4400);
DISPLAY 1.021277 (-5725 4400);
PAINT ORANGE (-5725 4400);
DISPLAY INVISIBLE (-5725 4400);
FORCEPROP 2 LAST CDS_LIB mstr_standard
J 0
(-5775 4325);
PAINT ORANGE (-5775 4325);
DISPLAY INVISIBLE (-5775 4325);
FORCEPROP 1 LAST OFFPAGE TRUE
J 0
(-5450 4200);
PAINT GREEN (-5450 4200);
DISPLAY INVISIBLE (-5450 4200);
FORCEPROP 1 LAST COMMENT_BODY TRUE
J 0
(-5675 4250);
DISPLAY 1.404255 (-5675 4250);
PAINT PEACH (-5675 4250);
DISPLAY INVISIBLE (-5675 4250);
FORCEADD RES..2
(-2200 1100);
FORCEPROP 1 LAST PART_NUMBER G21796-016
J 0
(-2160 975);
DISPLAY 0.617021 (-2160 975);
PAINT BLUE (-2160 975);
FORCEPROP 1 LAST PACK_TYPE 0402
J 0
(-2160 925);
DISPLAY 0.617021 (-2160 925);
PAINT SKYBLUE (-2160 925);
FORCEPROP 1 LAST MATERIAL CHIP
J 0
(-2160 1025);
DISPLAY 0.617021 (-2160 1025);
PAINT SKYBLUE (-2160 1025);
FORCEPROP 1 LAST WATTAGE 1/16W
J 0
(-2160 1075);
DISPLAY 0.617021 (-2160 1075);
PAINT SKYBLUE (-2160 1075);
FORCEPROP 1 LASTPIN (-2200 1000) $PN 2
J 0
(-2195 1010);
DISPLAY 0.617021 (-2195 1010);
PAINT ORANGE (-2195 1010);
FORCEPROP 1 LAST TOLERANCE 1%
J 0
(-2155 1125);
DISPLAY 0.617021 (-2155 1125);
PAINT SKYBLUE (-2155 1125);
FORCEPROP 1 LASTPIN (-2200 1200) $PN 1
J 0
(-2195 1162);
DISPLAY 0.617021 (-2195 1162);
PAINT ORANGE (-2195 1162);
FORCEPROP 1 LAST LOCATION R2N6
J 0
(-2155 1225);
DISPLAY 0.617021 (-2155 1225);
PAINT AQUA (-2155 1225);
FORCEPROP 1 LAST VALUE 10.0K
J 0
(-2155 1175);
DISPLAY 0.617021 (-2155 1175);
PAINT SKYBLUE (-2155 1175);
FORCEPROP 2 LAST SEC 1
J 0
(-2150 1325);
DISPLAY 0.680851 (-2150 1325);
PAINT MONO (-2150 1325);
DISPLAY INVISIBLE (-2150 1325);
FORCEPROP 2 LAST SEC_TYPE 0402
J 0
(-2150 1325);
DISPLAY 1.021277 (-2150 1325);
PAINT ORANGE (-2150 1325);
DISPLAY INVISIBLE (-2150 1325);
FORCEPROP 1 LAST PATH I128
J 0
(-2150 1275);
DISPLAY 0.978723 (-2150 1275);
PAINT WHITE (-2150 1275);
DISPLAY INVISIBLE (-2150 1275);
FORCEPROP 2 LAST CDS_LOCATION R2N6
J 0
(-2155 1225);
DISPLAY 0.617021 (-2155 1225);
PAINT AQUA (-2155 1225);
DISPLAY INVISIBLE (-2155 1225);
FORCEPROP 2 LAST CDS_LIB mstr_discrete
J 0
(-2200 1100);
PAINT MONO (-2200 1100);
DISPLAY INVISIBLE (-2200 1100);
FORCEPROP 2 LAST ROOM SB
J 0
(-2200 1100);
PAINT MONO (-2200 1100);
DISPLAY INVISIBLE (-2200 1100);
FORCEPROP 2 LAST BOM_COST SB
J 0
(-2250 950);
PAINT MONO (-2250 950);
DISPLAY INVISIBLE (-2250 950);
FORCEADD P3V3_STBY..1
(-2200 1275);
FORCEPROP 3 LASTPIN (-2200 1225) SIG_NAME P3V3_STBY\g
J 0
(-2190 1235);
DISPLAY 0.659574 (-2190 1235);
PAINT MONO (-2190 1235);
DISPLAY INVISIBLE (-2190 1235);
FORCEPROP 1 LAST SIZE 1B
J 0
(-2155 1297);
DISPLAY 0.340426 (-2155 1297);
PAINT GREEN (-2155 1297);
DISPLAY INVISIBLE (-2155 1297);
FORCEPROP 2 LAST CDS_LIB mstr_symbols
J 0
(-2200 1275);
PAINT ORANGE (-2200 1275);
DISPLAY INVISIBLE (-2200 1275);
FORCEPROP 1 LAST PATH I129
J 0
(-2155 1277);
DISPLAY 0.340426 (-2155 1277);
PAINT GREEN (-2155 1277);
DISPLAY INVISIBLE (-2155 1277);
FORCEPROP 1 LAST VOLTAGE 3.3V
J 0
(-2245 1232);
DISPLAY 0.340426 (-2245 1232);
PAINT SKYBLUE (-2245 1232);
DISPLAY INVISIBLE (-2245 1232);
FORCEPROP 1 LAST BODY_TYPE PLUMBING
J 0
(-2245 1232);
DISPLAY 0.340426 (-2245 1232);
PAINT GREEN (-2245 1232);
DISPLAY INVISIBLE (-2245 1232);
FORCEPROP 1 LAST HDL_POWER P3V3_STBY
J 0
(-2500 1150);
DISPLAY 0.872340 (-2500 1150);
PAINT ORANGE (-2500 1150);
DISPLAY INVISIBLE (-2500 1150);
FORCEADD OFFPAGE..5
(-7375 3975);
FORCEPROP 2 LAST $XR2 145 
J 0
(-7900 3975);
DISPLAY 0.638298 (-7900 3975);
PAINT MONO (-7900 3975);
FORCEPROP 2 LAST $XR1 157 
J 0
(-7780 3975);
DISPLAY 0.638298 (-7780 3975);
PAINT MONO (-7780 3975);
FORCEPROP 2 LAST $XR0 135 
J 0
(-7660 3975);
DISPLAY 0.638298 (-7660 3975);
PAINT MONO (-7660 3975);
FORCEPROP 2 LAST CDS_LIB mstr_standard
J 0
(-7375 3975);
PAINT ORANGE (-7375 3975);
DISPLAY INVISIBLE (-7375 3975);
FORCEPROP 2 LAST PATH I130
J 0
(-7325 4050);
DISPLAY 1.021277 (-7325 4050);
PAINT ORANGE (-7325 4050);
DISPLAY INVISIBLE (-7325 4050);
FORCEPROP 1 LAST OFFPAGE TRUE
J 0
(-7050 3850);
PAINT GREEN (-7050 3850);
DISPLAY INVISIBLE (-7050 3850);
FORCEPROP 1 LAST COMMENT_BODY TRUE
J 0
(-7275 3900);
DISPLAY 1.404255 (-7275 3900);
PAINT PEACH (-7275 3900);
DISPLAY INVISIBLE (-7275 3900);
FORCEADD RES..1
(-6625 3975);
FORCEPROP 0 LAST POP NOPOP
J 0
(-6750 3825);
DISPLAY 0.638298 (-6750 3825);
PAINT RED (-6750 3825);
FORCEPROP 1 LAST MATERIAL CHIP
J 0
(-6775 3875);
DISPLAY 0.617021 (-6775 3875);
PAINT SKYBLUE (-6775 3875);
FORCEPROP 1 LAST LOCATION R7D23
J 0
(-6900 3925);
DISPLAY 0.617021 (-6900 3925);
PAINT AQUA (-6900 3925);
FORCEPROP 1 LASTPIN (-6725 3975) $PN 1
J 0
(-6713 3987);
DISPLAY 0.617021 (-6713 3987);
PAINT ORANGE (-6713 3987);
FORCEPROP 1 LAST VALUE 0.0
J 2
(-6675 3925);
DISPLAY 0.617021 (-6675 3925);
PAINT SKYBLUE (-6675 3925);
FORCEPROP 1 LAST TOLERANCE 5%
J 0
(-6625 3925);
DISPLAY 0.617021 (-6625 3925);
PAINT SKYBLUE (-6625 3925);
FORCEPROP 1 LAST WATTAGE 1/16W
J 2
(-6775 3875);
DISPLAY 0.617021 (-6775 3875);
PAINT SKYBLUE (-6775 3875);
FORCEPROP 1 LASTPIN (-6525 3975) $PN 2
J 0
(-6563 3987);
DISPLAY 0.617021 (-6563 3987);
PAINT ORANGE (-6563 3987);
FORCEPROP 1 LAST PART_NUMBER G21497-005
J 0
(-6675 3875);
DISPLAY 0.617021 (-6675 3875);
PAINT BLUE (-6675 3875);
FORCEPROP 1 LAST PACK_TYPE 0402
J 0
(-6550 3925);
DISPLAY 0.617021 (-6550 3925);
PAINT SKYBLUE (-6550 3925);
FORCEPROP 1 LAST PATH I131
J 0
(-6675 4125);
DISPLAY 0.978723 (-6675 4125);
PAINT WHITE (-6675 4125);
DISPLAY INVISIBLE (-6675 4125);
FORCEPROP 2 LAST SEC 1
J 0
(-6675 4175);
DISPLAY 0.680851 (-6675 4175);
PAINT MONO (-6675 4175);
DISPLAY INVISIBLE (-6675 4175);
FORCEPROP 2 LAST SEC_TYPE 0402
J 0
(-6675 4175);
DISPLAY 1.021277 (-6675 4175);
PAINT ORANGE (-6675 4175);
DISPLAY INVISIBLE (-6675 4175);
FORCEPROP 2 LAST BOM_COST SB
J 0
(-6675 4125);
DISPLAY 1.021277 (-6675 4125);
PAINT ORANGE (-6675 4125);
DISPLAY INVISIBLE (-6675 4125);
FORCEPROP 2 LAST ROOM SB
J 0
(-6675 4075);
DISPLAY 1.021277 (-6675 4075);
PAINT ORANGE (-6675 4075);
DISPLAY INVISIBLE (-6675 4075);
FORCEPROP 2 LAST CDS_LIB mstr_discrete
J 0
(-6625 3975);
PAINT ORANGE (-6625 3975);
DISPLAY INVISIBLE (-6625 3975);
FORCEPROP 2 LAST CDS_LOCATION R7D23
J 0
(-6675 4025);
DISPLAY 0.617021 (-6675 4025);
PAINT AQUA (-6675 4025);
DISPLAY INVISIBLE (-6675 4025);
FORCEADD OFFPAGE..1
(-5775 4175);
FORCEPROP 2 LAST $XR2 190 
J 0
(-6116 4139);
DISPLAY 0.638298 (-6116 4139);
PAINT MONO (-6116 4139);
FORCEPROP 2 LAST $XR1 144 
J 0
(-6116 4175);
DISPLAY 0.638298 (-6116 4175);
PAINT MONO (-6116 4175);
FORCEPROP 2 LAST $XR0 21 
J 0
(-5996 4175);
DISPLAY 0.638298 (-5996 4175);
PAINT MONO (-5996 4175);
FORCEPROP 2 LAST CDS_LIB mstr_standard
J 0
(-5775 4175);
PAINT MONO (-5775 4175);
DISPLAY INVISIBLE (-5775 4175);
FORCEPROP 2 LAST PATH I132
J 0
(-6025 4225);
DISPLAY 1.021277 (-6025 4225);
PAINT ORANGE (-6025 4225);
DISPLAY INVISIBLE (-6025 4225);
FORCEPROP 1 LAST OFFPAGE TRUE
J 0
(-5450 4050);
PAINT GREEN (-5450 4050);
DISPLAY INVISIBLE (-5450 4050);
FORCEPROP 1 LAST COMMENT_BODY TRUE
J 0
(-5650 4075);
DISPLAY 1.404255 (-5650 4075);
PAINT PEACH (-5650 4075);
DISPLAY INVISIBLE (-5650 4075);
FORCEADD OFFPAGE..5
(-5775 3875);
FORCEPROP 2 LAST $XR0 118 
J 0
(-6060 3875);
DISPLAY 0.638298 (-6060 3875);
PAINT MONO (-6060 3875);
FORCEPROP 2 LAST PATH I133
J 0
(-5725 3950);
DISPLAY 1.021277 (-5725 3950);
PAINT ORANGE (-5725 3950);
DISPLAY INVISIBLE (-5725 3950);
FORCEPROP 2 LAST CDS_LIB mstr_standard
J 0
(-5775 3875);
PAINT ORANGE (-5775 3875);
DISPLAY INVISIBLE (-5775 3875);
FORCEPROP 1 LAST OFFPAGE TRUE
J 0
(-5450 3750);
PAINT GREEN (-5450 3750);
DISPLAY INVISIBLE (-5450 3750);
FORCEPROP 1 LAST COMMENT_BODY TRUE
J 0
(-5675 3800);
DISPLAY 1.404255 (-5675 3800);
PAINT PEACH (-5675 3800);
DISPLAY INVISIBLE (-5675 3800);
FORCEADD P3V3_STBY..1
(-5200 625);
FORCEPROP 3 LASTPIN (-5200 575) SIG_NAME P3V3_STBY\g
J 0
(-5190 585);
DISPLAY 0.659574 (-5190 585);
PAINT MONO (-5190 585);
DISPLAY INVISIBLE (-5190 585);
FORCEPROP 1 LAST SIZE 1B
J 0
(-5155 647);
DISPLAY 0.340426 (-5155 647);
PAINT GREEN (-5155 647);
DISPLAY INVISIBLE (-5155 647);
FORCEPROP 1 LAST PATH I135
J 0
(-5155 627);
DISPLAY 0.340426 (-5155 627);
PAINT GREEN (-5155 627);
DISPLAY INVISIBLE (-5155 627);
FORCEPROP 2 LAST CDS_LIB mstr_symbols
J 0
(-5200 625);
PAINT ORANGE (-5200 625);
DISPLAY INVISIBLE (-5200 625);
FORCEPROP 1 LAST VOLTAGE 3.3V
J 0
(-5245 582);
DISPLAY 0.340426 (-5245 582);
PAINT SKYBLUE (-5245 582);
DISPLAY INVISIBLE (-5245 582);
FORCEPROP 1 LAST BODY_TYPE PLUMBING
J 0
(-5245 582);
DISPLAY 0.340426 (-5245 582);
PAINT GREEN (-5245 582);
DISPLAY INVISIBLE (-5245 582);
FORCEPROP 1 LAST HDL_POWER P3V3_STBY
J 0
(-5500 500);
DISPLAY 0.872340 (-5500 500);
PAINT ORANGE (-5500 500);
DISPLAY INVISIBLE (-5500 500);
FORCEADD CAP_A..1
(-5200 375);
FORCEPROP 1 LAST PART_NUMBER A36096-030
J 0
(-5150 225);
DISPLAY 0.617021 (-5150 225);
PAINT BLUE (-5150 225);
FORCEPROP 1 LAST TOLERANCE 10%
J 0
(-5150 325);
DISPLAY 0.617021 (-5150 325);
PAINT SKYBLUE (-5150 325);
FORCEPROP 1 LAST PACK_TYPE 0402V
J 0
(-5150 175);
DISPLAY 0.617021 (-5150 175);
PAINT SKYBLUE (-5150 175);
FORCEPROP 1 LAST VOLTAGE 16V
J 0
(-5150 375);
DISPLAY 0.617021 (-5150 375);
PAINT SKYBLUE (-5150 375);
FORCEPROP 1 LAST MATERIAL X7R
J 0
(-5150 275);
DISPLAY 0.617021 (-5150 275);
PAINT SKYBLUE (-5150 275);
FORCEPROP 1 LASTPIN (-5200 275) $PN 2
J 0
(-5190 255);
DISPLAY 0.617021 (-5190 255);
PAINT ORANGE (-5190 255);
FORCEPROP 1 LAST LOCATION C7D1
J 0
(-5150 475);
DISPLAY 0.617021 (-5150 475);
PAINT AQUA (-5150 475);
FORCEPROP 1 LAST VALUE 0.1UF
J 0
(-5150 425);
DISPLAY 0.617021 (-5150 425);
PAINT SKYBLUE (-5150 425);
FORCEPROP 1 LASTPIN (-5200 475) $PN 1
J 0
(-5190 455);
DISPLAY 0.617021 (-5190 455);
PAINT ORANGE (-5190 455);
FORCEPROP 1 LAST PATH I136
J 0
(-5150 525);
DISPLAY 0.978723 (-5150 525);
PAINT WHITE (-5150 525);
DISPLAY INVISIBLE (-5150 525);
FORCEPROP 2 LAST ROOM SB
J 0
(-5150 525);
DISPLAY 1.021277 (-5150 525);
PAINT ORANGE (-5150 525);
DISPLAY INVISIBLE (-5150 525);
FORCEPROP 2 LAST BOM_COST SB
J 0
(-5150 575);
DISPLAY 1.021277 (-5150 575);
PAINT ORANGE (-5150 575);
DISPLAY INVISIBLE (-5150 575);
FORCEPROP 2 LAST CDS_SEC 1
J 0
(-5150 525);
PAINT ORANGE (-5150 525);
DISPLAY INVISIBLE (-5150 525);
FORCEPROP 2 LAST SEC 1
J 0
(-5150 575);
DISPLAY 0.680851 (-5150 575);
PAINT MONO (-5150 575);
DISPLAY INVISIBLE (-5150 575);
FORCEPROP 2 LAST SEC_TYPE 0402V
J 0
(-5150 575);
DISPLAY 1.021277 (-5150 575);
PAINT ORANGE (-5150 575);
DISPLAY INVISIBLE (-5150 575);
FORCEPROP 2 LAST CDS_LOCATION C7D1
J 0
(-5150 475);
DISPLAY 0.617021 (-5150 475);
PAINT AQUA (-5150 475);
DISPLAY INVISIBLE (-5150 475);
FORCEPROP 2 LAST CDS_LIB dev_discrete
J 0
(-5200 375);
PAINT ORANGE (-5200 375);
DISPLAY INVISIBLE (-5200 375);
FORCEADD GND..1
(-5200 125);
FORCEPROP 3 LASTPIN (-5200 175) SIG_NAME GND\g
J 0
(-5190 185);
DISPLAY 0.659574 (-5190 185);
PAINT MONO (-5190 185);
DISPLAY INVISIBLE (-5190 185);
FORCEPROP 1 LAST VOLTAGE 0.0V
J 0
(-5245 82);
DISPLAY 0.340426 (-5245 82);
PAINT SKYBLUE (-5245 82);
DISPLAY INVISIBLE (-5245 82);
FORCEPROP 2 LAST CDS_LIB mstr_symbols
J 0
(-5200 125);
PAINT ORANGE (-5200 125);
DISPLAY INVISIBLE (-5200 125);
FORCEPROP 1 LAST SIZE 1B
J 0
(-5125 75);
DISPLAY 0.872340 (-5125 75);
PAINT AQUA (-5125 75);
DISPLAY INVISIBLE (-5125 75);
FORCEPROP 1 LAST PATH I137
J 0
(-5125 125);
DISPLAY 0.872340 (-5125 125);
PAINT AQUA (-5125 125);
DISPLAY INVISIBLE (-5125 125);
FORCEPROP 1 LAST BODY_TYPE PLUMBING
J 0
(-5245 82);
DISPLAY 0.340426 (-5245 82);
PAINT GREEN (-5245 82);
DISPLAY INVISIBLE (-5245 82);
FORCEPROP 1 LAST HDL_POWER GND
J 0
(-5200 275);
DISPLAY 0.872340 (-5200 275);
PAINT GREEN (-5200 275);
DISPLAY INVISIBLE (-5200 275);
FORCEADD OFFPAGE..1
(-5800 1075);
FORCEPROP 2 LAST $XR0 118 
J 0
(-6052 1075);
DISPLAY 0.638298 (-6052 1075);
PAINT MONO (-6052 1075);
FORCEPROP 2 LAST PATH I138
J 0
(-5750 1150);
DISPLAY 1.021277 (-5750 1150);
PAINT ORANGE (-5750 1150);
DISPLAY INVISIBLE (-5750 1150);
FORCEPROP 2 LAST CDS_LIB mstr_standard
J 0
(-5800 1075);
PAINT ORANGE (-5800 1075);
DISPLAY INVISIBLE (-5800 1075);
FORCEPROP 1 LAST OFFPAGE TRUE
J 0
(-5475 950);
DISPLAY 0.872340 (-5475 950);
PAINT GREEN (-5475 950);
DISPLAY INVISIBLE (-5475 950);
FORCEPROP 1 LAST COMMENT_BODY TRUE
J 0
(-5675 975);
DISPLAY 0.872340 (-5675 975);
PAINT GREEN (-5675 975);
DISPLAY INVISIBLE (-5675 975);
FORCEADD OFFPAGE..2
(-3650 1075);
FORCEPROP 2 LAST $XR3 56 
J 0
(-3131 1075);
DISPLAY 0.638298 (-3131 1075);
PAINT MONO (-3131 1075);
FORCEPROP 2 LAST $XR2 22 
J 0
(-3221 1075);
DISPLAY 0.638298 (-3221 1075);
PAINT MONO (-3221 1075);
FORCEPROP 2 LAST $XR1 254 
J 0
(-3341 1075);
DISPLAY 0.638298 (-3341 1075);
PAINT MONO (-3341 1075);
FORCEPROP 2 LAST $XR0 111 
J 0
(-3461 1075);
DISPLAY 0.638298 (-3461 1075);
PAINT MONO (-3461 1075);
FORCEPROP 2 LAST PATH I140
J 0
(-3475 1150);
DISPLAY 1.021277 (-3475 1150);
PAINT ORANGE (-3475 1150);
DISPLAY INVISIBLE (-3475 1150);
FORCEPROP 2 LAST CDS_LIB mstr_standard
J 0
(-3650 1075);
PAINT ORANGE (-3650 1075);
DISPLAY INVISIBLE (-3650 1075);
FORCEPROP 1 LAST OFFPAGE TRUE
J 0
(-3325 950);
DISPLAY 1.170213 (-3325 950);
PAINT GREEN (-3325 950);
DISPLAY INVISIBLE (-3325 950);
FORCEPROP 1 LAST COMMENT_BODY TRUE
J 0
(-3695 980);
DISPLAY 1.170213 (-3695 980);
PAINT PEACH (-3695 980);
DISPLAY INVISIBLE (-3695 980);
FORCEADD OFFPAGE..3
R 2
(-5675 2875);
FORCEPROP 2 LAST $XR2 112 
J 0
(-6195 2875);
DISPLAY 0.638298 (-6195 2875);
PAINT MONO (-6195 2875);
FORCEPROP 2 LAST $XR1 254 
J 0
(-6075 2875);
DISPLAY 0.638298 (-6075 2875);
PAINT MONO (-6075 2875);
FORCEPROP 2 LAST $XR0 111 
J 0
(-5955 2875);
DISPLAY 0.638298 (-5955 2875);
PAINT MONO (-5955 2875);
FORCEPROP 2 LAST PATH I141
J 0
(-5625 2950);
DISPLAY 1.021277 (-5625 2950);
PAINT ORANGE (-5625 2950);
DISPLAY INVISIBLE (-5625 2950);
FORCEPROP 2 LAST CDS_LIB mstr_standard
J 0
(-5675 2875);
PAINT ORANGE (-5675 2875);
DISPLAY INVISIBLE (-5675 2875);
FORCEPROP 1 LAST OFFPAGE TRUE
J 2
(-6000 2750);
DISPLAY 0.872340 (-6000 2750);
PAINT GREEN (-6000 2750);
DISPLAY INVISIBLE (-6000 2750);
FORCEPROP 1 LAST COMMENT_BODY TRUE
J 2
(-5625 2775);
DISPLAY 0.872340 (-5625 2775);
PAINT GREEN (-5625 2775);
DISPLAY INVISIBLE (-5625 2775);
FORCEADD 74CBTLV1G125..1
(-4575 1075);
FORCEPROP 1 LAST POWER_GROUP VCC=P3V3_STBY;GND=GND;
J 0
(-4800 875);
DISPLAY 0.617021 (-4800 875);
PAINT ORANGE (-4800 875);
FORCEPROP 2 LASTPIN (-4325 1075) $PN 4
J 0
(-4315 1085);
DISPLAY 0.617021 (-4315 1085);
PAINT MONO (-4315 1085);
FORCEPROP 1 LAST LOCATION U7D1
J 0
(-4641 1206);
DISPLAY 0.617021 (-4641 1206);
PAINT AQUA (-4641 1206);
FORCEPROP 1 LAST MATERIAL IC
J 0
(-4775 1195);
DISPLAY 0.617021 (-4775 1195);
PAINT SKYBLUE (-4775 1195);
FORCEPROP 2 LASTPIN (-4825 1075) $PN 2
J 2
(-4835 1085);
DISPLAY 0.617021 (-4835 1085);
PAINT MONO (-4835 1085);
FORCEPROP 2 LASTPIN (-4825 1025) $PN 1
J 2
(-4835 1035);
DISPLAY 0.617021 (-4835 1035);
PAINT MONO (-4835 1035);
FORCEPROP 1 LAST PART_NUMBER C88177-001
J 0
(-4740 935);
DISPLAY 0.617021 (-4740 935);
PAINT BLUE (-4740 935);
FORCEPROP 1 LAST PACK_TYPE SMLF
J 0
(-4725 820);
DISPLAY 0.617021 (-4725 820);
PAINT SKYBLUE (-4725 820);
FORCEPROP 2 LAST $SEC 1
J 0
(-4475 1250);
PAINT MONO (-4475 1250);
DISPLAY INVISIBLE (-4475 1250);
FORCEPROP 2 LAST CDS_SEC 1
J 0
(-4475 1250);
PAINT MONO (-4475 1250);
DISPLAY INVISIBLE (-4475 1250);
FORCEPROP 2 LAST CDS_LIB mstr_ttl
J 0
(-4575 1075);
PAINT ORANGE (-4575 1075);
DISPLAY INVISIBLE (-4575 1075);
FORCEPROP 1 LAST PATH I142
J 0
(-4475 1195);
DISPLAY 0.872340 (-4475 1195);
PAINT PINK (-4475 1195);
DISPLAY INVISIBLE (-4475 1195);
FORCEPROP 2 LAST CDS_LOCATION U7D1
J 0
(-4641 1206);
DISPLAY 0.617021 (-4641 1206);
PAINT AQUA (-4641 1206);
DISPLAY INVISIBLE (-4641 1206);
FORCEPROP 0 LAST BOM_COST DEBUG
J 0
(-4750 1400);
DISPLAY 1.021277 (-4750 1400);
PAINT ORANGE (-4750 1400);
DISPLAY INVISIBLE (-4750 1400);
FORCEPROP 0 LAST ROOM DEBUG
J 0
(-4750 1400);
DISPLAY 1.021277 (-4750 1400);
PAINT ORANGE (-4750 1400);
DISPLAY INVISIBLE (-4750 1400);
FORCEADD RES..2
(-5175 1275);
FORCEPROP 1 LAST LOCATION R7C23
J 0
(-5130 1400);
DISPLAY 0.617021 (-5130 1400);
PAINT AQUA (-5130 1400);
FORCEPROP 1 LAST VALUE 10.0K
J 0
(-5130 1350);
DISPLAY 0.617021 (-5130 1350);
PAINT SKYBLUE (-5130 1350);
FORCEPROP 1 LAST TOLERANCE 1%
J 0
(-5130 1300);
DISPLAY 0.617021 (-5130 1300);
PAINT SKYBLUE (-5130 1300);
FORCEPROP 1 LAST PACK_TYPE 0402
J 0
(-5135 1100);
DISPLAY 0.617021 (-5135 1100);
PAINT SKYBLUE (-5135 1100);
FORCEPROP 1 LAST MATERIAL CHIP
J 0
(-5135 1200);
DISPLAY 0.617021 (-5135 1200);
PAINT SKYBLUE (-5135 1200);
FORCEPROP 1 LASTPIN (-5175 1375) $PN 1
J 0
(-5170 1337);
DISPLAY 0.617021 (-5170 1337);
PAINT ORANGE (-5170 1337);
FORCEPROP 1 LASTPIN (-5175 1175) $PN 2
J 0
(-5170 1185);
DISPLAY 0.617021 (-5170 1185);
PAINT ORANGE (-5170 1185);
FORCEPROP 1 LAST WATTAGE 1/16W
J 0
(-5135 1250);
DISPLAY 0.617021 (-5135 1250);
PAINT SKYBLUE (-5135 1250);
FORCEPROP 1 LAST PART_NUMBER G21796-016
J 0
(-5135 1150);
DISPLAY 0.617021 (-5135 1150);
PAINT BLUE (-5135 1150);
FORCEPROP 2 LAST SEC_TYPE 0402
J 0
(-5125 1500);
DISPLAY 1.021277 (-5125 1500);
PAINT ORANGE (-5125 1500);
DISPLAY INVISIBLE (-5125 1500);
FORCEPROP 2 LAST SEC 1
J 0
(-5125 1500);
DISPLAY 0.680851 (-5125 1500);
PAINT MONO (-5125 1500);
DISPLAY INVISIBLE (-5125 1500);
FORCEPROP 1 LAST PATH I144
J 0
(-5125 1450);
DISPLAY 0.978723 (-5125 1450);
PAINT WHITE (-5125 1450);
DISPLAY INVISIBLE (-5125 1450);
FORCEPROP 2 LAST CDS_LOCATION R7C23
J 0
(-5130 1400);
DISPLAY 0.617021 (-5130 1400);
PAINT AQUA (-5130 1400);
DISPLAY INVISIBLE (-5130 1400);
FORCEPROP 2 LAST CDS_LIB mstr_discrete
J 0
(-5175 1275);
PAINT ORANGE (-5175 1275);
DISPLAY INVISIBLE (-5175 1275);
FORCEPROP 2 LAST ROOM SB
J 0
(-5175 1275);
PAINT MONO (-5175 1275);
DISPLAY INVISIBLE (-5175 1275);
FORCEPROP 2 LAST BOM_COST SB
J 0
(-5225 1125);
PAINT MONO (-5225 1125);
DISPLAY INVISIBLE (-5225 1125);
FORCEADD P3V3_STBY..1
(-5175 1450);
FORCEPROP 3 LASTPIN (-5175 1400) SIG_NAME P3V3_STBY\g
J 0
(-5165 1410);
DISPLAY 0.659574 (-5165 1410);
PAINT MONO (-5165 1410);
DISPLAY INVISIBLE (-5165 1410);
FORCEPROP 2 LAST CDS_LIB mstr_symbols
J 0
(-5175 1450);
PAINT ORANGE (-5175 1450);
DISPLAY INVISIBLE (-5175 1450);
FORCEPROP 1 LAST SIZE 1B
J 0
(-5130 1472);
DISPLAY 0.340426 (-5130 1472);
PAINT GREEN (-5130 1472);
DISPLAY INVISIBLE (-5130 1472);
FORCEPROP 1 LAST PATH I145
J 0
(-5130 1452);
DISPLAY 0.340426 (-5130 1452);
PAINT GREEN (-5130 1452);
DISPLAY INVISIBLE (-5130 1452);
FORCEPROP 1 LAST VOLTAGE 3.3V
J 0
(-5220 1407);
DISPLAY 0.340426 (-5220 1407);
PAINT SKYBLUE (-5220 1407);
DISPLAY INVISIBLE (-5220 1407);
FORCEPROP 1 LAST BODY_TYPE PLUMBING
J 0
(-5220 1407);
DISPLAY 0.340426 (-5220 1407);
PAINT GREEN (-5220 1407);
DISPLAY INVISIBLE (-5220 1407);
FORCEPROP 1 LAST HDL_POWER P3V3_STBY
J 0
(-5475 1325);
DISPLAY 0.872340 (-5475 1325);
PAINT ORANGE (-5475 1325);
DISPLAY INVISIBLE (-5475 1325);
FORCEADD OFFPAGE..1
(-5650 2100);
FORCEPROP 2 LAST $XR0 188 
J 0
(-5932 2100);
DISPLAY 0.638298 (-5932 2100);
PAINT MONO (-5932 2100);
FORCEPROP 2 LAST PATH I152
J 0
(-5600 2175);
DISPLAY 1.021277 (-5600 2175);
PAINT ORANGE (-5600 2175);
DISPLAY INVISIBLE (-5600 2175);
FORCEPROP 2 LAST CDS_LIB mstr_standard
J 0
(-5650 2100);
PAINT ORANGE (-5650 2100);
DISPLAY INVISIBLE (-5650 2100);
FORCEPROP 1 LAST OFFPAGE TRUE
J 0
(-5325 1975);
PAINT GREEN (-5325 1975);
DISPLAY INVISIBLE (-5325 1975);
FORCEPROP 1 LAST COMMENT_BODY TRUE
J 0
(-5525 2000);
DISPLAY 1.404255 (-5525 2000);
PAINT PEACH (-5525 2000);
DISPLAY INVISIBLE (-5525 2000);
FORCEADD OFFPAGE..1
(-5650 2050);
FORCEPROP 2 LAST $XR0 188 
J 0
(-5932 2050);
DISPLAY 0.638298 (-5932 2050);
PAINT MONO (-5932 2050);
FORCEPROP 2 LAST PATH I153
J 0
(-5600 2125);
DISPLAY 1.021277 (-5600 2125);
PAINT ORANGE (-5600 2125);
DISPLAY INVISIBLE (-5600 2125);
FORCEPROP 2 LAST CDS_LIB mstr_standard
J 0
(-5650 2050);
PAINT ORANGE (-5650 2050);
DISPLAY INVISIBLE (-5650 2050);
FORCEPROP 1 LAST OFFPAGE TRUE
J 0
(-5325 1925);
PAINT GREEN (-5325 1925);
DISPLAY INVISIBLE (-5325 1925);
FORCEPROP 1 LAST COMMENT_BODY TRUE
J 0
(-5525 1950);
DISPLAY 1.404255 (-5525 1950);
PAINT PEACH (-5525 1950);
DISPLAY INVISIBLE (-5525 1950);
FORCEADD OFFPAGE..2
(-2525 2100);
FORCEPROP 2 LAST $XR0 188 
J 0
(-2336 2100);
DISPLAY 0.638298 (-2336 2100);
PAINT MONO (-2336 2100);
FORCEPROP 2 LAST PATH I160
J 0
(-2350 2175);
DISPLAY 1.021277 (-2350 2175);
PAINT ORANGE (-2350 2175);
DISPLAY INVISIBLE (-2350 2175);
FORCEPROP 2 LAST CDS_LIB mstr_standard
J 0
(-2525 2100);
PAINT ORANGE (-2525 2100);
DISPLAY INVISIBLE (-2525 2100);
FORCEPROP 1 LAST OFFPAGE TRUE
J 0
(-2200 1975);
PAINT GREEN (-2200 1975);
DISPLAY INVISIBLE (-2200 1975);
FORCEPROP 1 LAST COMMENT_BODY TRUE
J 0
(-2570 2005);
DISPLAY 1.404255 (-2570 2005);
PAINT PEACH (-2570 2005);
DISPLAY INVISIBLE (-2570 2005);
FORCEADD OFFPAGE..2
(-2525 2050);
FORCEPROP 2 LAST $XR0 188 
J 0
(-2336 2050);
DISPLAY 0.638298 (-2336 2050);
PAINT MONO (-2336 2050);
FORCEPROP 2 LAST PATH I161
J 0
(-2350 2125);
DISPLAY 1.021277 (-2350 2125);
PAINT ORANGE (-2350 2125);
DISPLAY INVISIBLE (-2350 2125);
FORCEPROP 2 LAST CDS_LIB mstr_standard
J 0
(-2525 2050);
PAINT ORANGE (-2525 2050);
DISPLAY INVISIBLE (-2525 2050);
FORCEPROP 1 LAST OFFPAGE TRUE
J 0
(-2200 1925);
PAINT GREEN (-2200 1925);
DISPLAY INVISIBLE (-2200 1925);
FORCEPROP 1 LAST COMMENT_BODY TRUE
J 0
(-2570 1955);
DISPLAY 1.404255 (-2570 1955);
PAINT PEACH (-2570 1955);
DISPLAY INVISIBLE (-2570 1955);
FORCEADD OFFPAGE..1
(-5800 1025);
FORCEPROP 2 LAST $XR1 190 
J 0
(-6172 1025);
DISPLAY 0.638298 (-6172 1025);
PAINT MONO (-6172 1025);
FORCEPROP 2 LAST $XR0 211 
J 0
(-6052 1025);
DISPLAY 0.638298 (-6052 1025);
PAINT MONO (-6052 1025);
FORCEPROP 2 LAST PATH I164
J 0
(-5750 1100);
DISPLAY 1.021277 (-5750 1100);
PAINT ORANGE (-5750 1100);
DISPLAY INVISIBLE (-5750 1100);
FORCEPROP 2 LAST CDS_LIB mstr_standard
J 0
(-5800 1025);
PAINT ORANGE (-5800 1025);
DISPLAY INVISIBLE (-5800 1025);
FORCEPROP 1 LAST OFFPAGE TRUE
J 0
(-5475 900);
DISPLAY 0.872340 (-5475 900);
PAINT GREEN (-5475 900);
DISPLAY INVISIBLE (-5475 900);
FORCEPROP 1 LAST COMMENT_BODY TRUE
J 0
(-5675 925);
DISPLAY 0.872340 (-5675 925);
PAINT GREEN (-5675 925);
DISPLAY INVISIBLE (-5675 925);
FORCEADD OFFPAGE..1
(-7375 4375);
FORCEPROP 2 LAST $XR3 145 
J 0
(-7956 4375);
DISPLAY 0.638298 (-7956 4375);
PAINT MONO (-7956 4375);
FORCEPROP 2 LAST $XR2 120 
J 0
(-7836 4375);
DISPLAY 0.638298 (-7836 4375);
PAINT MONO (-7836 4375);
FORCEPROP 2 LAST $XR1 133 
J 0
(-7716 4375);
DISPLAY 0.638298 (-7716 4375);
PAINT MONO (-7716 4375);
FORCEPROP 2 LAST $XR0 22 
J 0
(-7596 4375);
DISPLAY 0.638298 (-7596 4375);
PAINT MONO (-7596 4375);
FORCEPROP 2 LAST CDS_LIB mstr_standard
J 0
(-7375 4375);
PAINT ORANGE (-7375 4375);
DISPLAY INVISIBLE (-7375 4375);
FORCEPROP 2 LAST PATH I165
J 0
(-7325 4450);
DISPLAY 1.021277 (-7325 4450);
PAINT ORANGE (-7325 4450);
DISPLAY INVISIBLE (-7325 4450);
FORCEPROP 1 LAST OFFPAGE TRUE
J 0
(-7050 4250);
PAINT GREEN (-7050 4250);
DISPLAY INVISIBLE (-7050 4250);
FORCEPROP 1 LAST COMMENT_BODY TRUE
J 0
(-7250 4275);
DISPLAY 1.404255 (-7250 4275);
PAINT PEACH (-7250 4275);
DISPLAY INVISIBLE (-7250 4275);
FORCEADD OFFPAGE..5
(-7375 4075);
FORCEPROP 2 LAST $XR2 247 
J 0
(-7900 4075);
DISPLAY 0.638298 (-7900 4075);
PAINT MONO (-7900 4075);
FORCEPROP 2 LAST $XR1 190 
J 0
(-7780 4075);
DISPLAY 0.638298 (-7780 4075);
PAINT MONO (-7780 4075);
FORCEPROP 2 LAST $XR0 148 
J 0
(-7660 4075);
DISPLAY 0.638298 (-7660 4075);
PAINT MONO (-7660 4075);
FORCEPROP 2 LAST CDS_LIB mstr_standard
J 0
(-7375 4075);
PAINT ORANGE (-7375 4075);
DISPLAY INVISIBLE (-7375 4075);
FORCEPROP 2 LAST PATH I166
J 0
(-7650 4125);
DISPLAY 1.021277 (-7650 4125);
PAINT ORANGE (-7650 4125);
DISPLAY INVISIBLE (-7650 4125);
FORCEPROP 1 LAST OFFPAGE TRUE
J 0
(-7050 3950);
PAINT GREEN (-7050 3950);
DISPLAY INVISIBLE (-7050 3950);
FORCEPROP 1 LAST COMMENT_BODY TRUE
J 0
(-7275 4000);
DISPLAY 1.404255 (-7275 4000);
PAINT PEACH (-7275 4000);
DISPLAY INVISIBLE (-7275 4000);
FORCEADD RES..1
(-6650 4075);
FORCEPROP 1 LAST PACK_TYPE 0402
J 0
(-6550 4125);
DISPLAY 0.617021 (-6550 4125);
PAINT SKYBLUE (-6550 4125);
FORCEPROP 1 LAST PART_NUMBER G21497-005
J 0
(-6675 4175);
DISPLAY 0.617021 (-6675 4175);
PAINT BLUE (-6675 4175);
FORCEPROP 1 LAST TOLERANCE 5%
J 0
(-6625 4125);
DISPLAY 0.617021 (-6625 4125);
PAINT SKYBLUE (-6625 4125);
FORCEPROP 1 LAST VALUE 0.0
J 2
(-6675 4125);
DISPLAY 0.617021 (-6675 4125);
PAINT SKYBLUE (-6675 4125);
FORCEPROP 1 LAST LOCATION R7W1
J 0
(-6900 4125);
DISPLAY 0.617021 (-6900 4125);
PAINT AQUA (-6900 4125);
FORCEPROP 1 LASTPIN (-6750 4075) $PN 1
J 0
(-6738 4087);
DISPLAY 0.617021 (-6738 4087);
PAINT ORANGE (-6738 4087);
FORCEPROP 1 LAST WATTAGE 1/16W
J 2
(-6800 4175);
DISPLAY 0.617021 (-6800 4175);
PAINT SKYBLUE (-6800 4175);
FORCEPROP 1 LAST MATERIAL CHIP
J 0
(-6800 4175);
DISPLAY 0.617021 (-6800 4175);
PAINT SKYBLUE (-6800 4175);
FORCEPROP 1 LASTPIN (-6550 4075) $PN 2
J 0
(-6588 4087);
DISPLAY 0.617021 (-6588 4087);
PAINT ORANGE (-6588 4087);
FORCEPROP 2 LAST SEC 1
J 0
(-6700 4275);
DISPLAY 0.553191 (-6700 4275);
PAINT MONO (-6700 4275);
DISPLAY INVISIBLE (-6700 4275);
FORCEPROP 2 LAST CDS_LOCATION R7W1
J 0
(-6700 4125);
DISPLAY 0.617021 (-6700 4125);
PAINT AQUA (-6700 4125);
DISPLAY INVISIBLE (-6700 4125);
FORCEPROP 2 LAST CDS_LIB mstr_discrete
J 0
(-6650 4075);
PAINT ORANGE (-6650 4075);
DISPLAY INVISIBLE (-6650 4075);
FORCEPROP 2 LAST ROOM SB
J 0
(-6700 4175);
DISPLAY 1.021277 (-6700 4175);
PAINT ORANGE (-6700 4175);
DISPLAY INVISIBLE (-6700 4175);
FORCEPROP 2 LAST BOM_COST SB
J 0
(-6700 4225);
DISPLAY 1.021277 (-6700 4225);
PAINT ORANGE (-6700 4225);
DISPLAY INVISIBLE (-6700 4225);
FORCEPROP 2 LAST SEC_TYPE 0402
J 0
(-6700 4275);
DISPLAY 1.021277 (-6700 4275);
PAINT ORANGE (-6700 4275);
DISPLAY INVISIBLE (-6700 4275);
FORCEPROP 1 LAST PATH I167
J 0
(-6700 4225);
DISPLAY 0.978723 (-6700 4225);
PAINT WHITE (-6700 4225);
DISPLAY INVISIBLE (-6700 4225);
FORCEADD RES..1
(-2725 3650);
FORCEPROP 1 LAST TOLERANCE 5%
J 0
(-2675 3750);
DISPLAY 0.617021 (-2675 3750);
PAINT SKYBLUE (-2675 3750);
FORCEPROP 1 LAST VALUE 0.0
J 0
(-2775 3750);
DISPLAY 0.617021 (-2775 3750);
PAINT SKYBLUE (-2775 3750);
FORCEPROP 1 LASTPIN (-2825 3650) $PN 1
J 0
(-2813 3662);
DISPLAY 0.787234 (-2813 3662);
PAINT ORANGE (-2813 3662);
FORCEPROP 1 LAST LOCATION R1W30
J 0
(-2950 3750);
DISPLAY 0.617021 (-2950 3750);
PAINT AQUA (-2950 3750);
FORCEPROP 1 LAST MATERIAL EMPTY
J 0
(-2700 3500);
DISPLAY 0.617021 (-2700 3500);
PAINT RED (-2700 3500);
FORCEPROP 1 LAST WATTAGE 1/16W
J 0
(-2575 3750);
DISPLAY 0.617021 (-2575 3750);
PAINT SKYBLUE (-2575 3750);
FORCEPROP 1 LASTPIN (-2625 3650) $PN 2
J 0
(-2663 3662);
DISPLAY 0.787234 (-2663 3662);
PAINT ORANGE (-2663 3662);
FORCEPROP 1 LAST PACK_TYPE 0402
J 0
(-2525 3500);
DISPLAY 0.617021 (-2525 3500);
PAINT SKYBLUE (-2525 3500);
FORCEPROP 1 LAST PART_NUMBER G21497-005
J 0
(-2975 3500);
DISPLAY 0.617021 (-2975 3500);
PAINT BLUE (-2975 3500);
FORCEPROP 2 LAST SEC 1
J 0
(-2775 3850);
PAINT MONO (-2775 3850);
DISPLAY INVISIBLE (-2775 3850);
FORCEPROP 2 LAST SEC_TYPE 0402
J 0
(-2775 3850);
DISPLAY 1.021277 (-2775 3850);
PAINT ORANGE (-2775 3850);
DISPLAY INVISIBLE (-2775 3850);
FORCEPROP 1 LAST PATH I168
J 0
(-2775 3800);
DISPLAY 0.978723 (-2775 3800);
PAINT WHITE (-2775 3800);
DISPLAY INVISIBLE (-2775 3800);
FORCEPROP 2 LAST CDS_LIB mstr_discrete
J 0
(-2725 3650);
PAINT MONO (-2725 3650);
DISPLAY INVISIBLE (-2725 3650);
FORCEPROP 0 LAST ROOM NV_DIMM
J 0
(-2775 3850);
DISPLAY 1.021277 (-2775 3850);
PAINT ORANGE (-2775 3850);
DISPLAY INVISIBLE (-2775 3850);
FORCEPROP 0 LAST BOM_COST MEM_NV
J 0
(-2775 3950);
DISPLAY 1.021277 (-2775 3950);
PAINT ORANGE (-2775 3950);
DISPLAY INVISIBLE (-2775 3950);
FORCEPROP 2 LAST CDS_LOCATION R1W30
J 0
(-2775 3700);
DISPLAY 0.617021 (-2775 3700);
PAINT AQUA (-2775 3700);
DISPLAY INVISIBLE (-2775 3700);
FORCEADD OFFPAGE..4
(-1925 3650);
FORCEPROP 2 LAST $XR0 175 
J 0
(-1739 3650);
DISPLAY 0.638298 (-1739 3650);
PAINT MONO (-1739 3650);
FORCEPROP 2 LAST CDS_LIB mstr_standard
J 0
(-1925 3650);
PAINT MONO (-1925 3650);
DISPLAY INVISIBLE (-1925 3650);
FORCEPROP 2 LAST PATH I169
J 0
(-1750 3725);
DISPLAY 1.021277 (-1750 3725);
PAINT ORANGE (-1750 3725);
DISPLAY INVISIBLE (-1750 3725);
FORCEPROP 1 LAST OFFPAGE TRUE
J 0
(-1600 3525);
DISPLAY 0.872340 (-1600 3525);
PAINT GREEN (-1600 3525);
DISPLAY INVISIBLE (-1600 3525);
FORCEPROP 1 LAST COMMENT_BODY TRUE
J 0
(-1950 3550);
DISPLAY 0.872340 (-1950 3550);
PAINT GREEN (-1950 3550);
DISPLAY INVISIBLE (-1950 3550);
FORCEADD OFFPAGE..2
(-2525 2225);
FORCEPROP 2 LAST $XR0 188 
J 0
(-2186 2225);
DISPLAY 0.638298 (-2186 2225);
PAINT MONO (-2186 2225);
FORCEPROP 2 LAST CDS_LIB mstr_standard
J 0
(-2525 2225);
PAINT ORANGE (-2525 2225);
DISPLAY INVISIBLE (-2525 2225);
FORCEPROP 2 LAST PATH I170
J 0
(-2350 2300);
DISPLAY 1.021277 (-2350 2300);
PAINT ORANGE (-2350 2300);
DISPLAY INVISIBLE (-2350 2300);
FORCEPROP 1 LAST OFFPAGE TRUE
J 0
(-2200 2100);
PAINT GREEN (-2200 2100);
DISPLAY INVISIBLE (-2200 2100);
FORCEPROP 1 LAST COMMENT_BODY TRUE
J 0
(-2570 2130);
DISPLAY 1.404255 (-2570 2130);
PAINT PEACH (-2570 2130);
DISPLAY INVISIBLE (-2570 2130);
FORCEADD OFFPAGE..2
(-2525 2175);
FORCEPROP 2 LAST CDS_LIB mstr_standard
J 0
(-2525 2175);
PAINT ORANGE (-2525 2175);
DISPLAY INVISIBLE (-2525 2175);
FORCEPROP 2 LAST PATH I171
J 0
(-2325 2225);
DISPLAY 1.021277 (-2325 2225);
PAINT ORANGE (-2325 2225);
DISPLAY INVISIBLE (-2325 2225);
FORCEPROP 1 LAST OFFPAGE TRUE
J 0
(-2200 2050);
PAINT GREEN (-2200 2050);
DISPLAY INVISIBLE (-2200 2050);
FORCEPROP 1 LAST COMMENT_BODY TRUE
J 0
(-2570 2080);
DISPLAY 1.404255 (-2570 2080);
PAINT PEACH (-2570 2080);
DISPLAY INVISIBLE (-2570 2080);
FORCEPROP 2 LAST $XR0 188 
J 0
(-2336 2175);
DISPLAY 0.638298 (-2336 2175);
PAINT MONO (-2336 2175);
DISPLAY INVISIBLE (-2336 2175);
FORCEADD OFFPAGE..1
(-5650 2175);
FORCEPROP 2 LAST $XR0 188 
J 0
(-5932 2175);
DISPLAY 0.638298 (-5932 2175);
PAINT MONO (-5932 2175);
FORCEPROP 2 LAST CDS_LIB mstr_standard
J 0
(-5650 2175);
PAINT ORANGE (-5650 2175);
DISPLAY INVISIBLE (-5650 2175);
FORCEPROP 2 LAST PATH I172
J 0
(-5925 2225);
DISPLAY 1.021277 (-5925 2225);
PAINT ORANGE (-5925 2225);
DISPLAY INVISIBLE (-5925 2225);
FORCEPROP 1 LAST OFFPAGE TRUE
J 0
(-5325 2050);
PAINT GREEN (-5325 2050);
DISPLAY INVISIBLE (-5325 2050);
FORCEPROP 1 LAST COMMENT_BODY TRUE
J 0
(-5525 2075);
DISPLAY 1.404255 (-5525 2075);
PAINT PEACH (-5525 2075);
DISPLAY INVISIBLE (-5525 2075);
FORCEADD OFFPAGE..1
(-5650 2225);
FORCEPROP 2 LAST CDS_LIB mstr_standard
J 0
(-5650 2225);
PAINT ORANGE (-5650 2225);
DISPLAY INVISIBLE (-5650 2225);
FORCEPROP 2 LAST PATH I173
J 0
(-5925 2275);
DISPLAY 1.021277 (-5925 2275);
PAINT ORANGE (-5925 2275);
DISPLAY INVISIBLE (-5925 2275);
FORCEPROP 1 LAST OFFPAGE TRUE
J 0
(-5325 2100);
PAINT GREEN (-5325 2100);
DISPLAY INVISIBLE (-5325 2100);
FORCEPROP 1 LAST COMMENT_BODY TRUE
J 0
(-5525 2125);
DISPLAY 1.404255 (-5525 2125);
PAINT PEACH (-5525 2125);
DISPLAY INVISIBLE (-5525 2125);
FORCEPROP 2 LAST $XR0 188 
J 0
(-6076 2225);
DISPLAY 0.638298 (-6076 2225);
PAINT MONO (-6076 2225);
DISPLAY INVISIBLE (-6076 2225);
FORCEADD RES..1
(-6650 4225);
FORCEPROP 1 LAST TOLERANCE 5%
J 0
(-6625 4275);
DISPLAY 0.617021 (-6625 4275);
PAINT SKYBLUE (-6625 4275);
FORCEPROP 1 LAST PART_NUMBER G21497-005
J 0
(-6675 4325);
DISPLAY 0.617021 (-6675 4325);
PAINT BLUE (-6675 4325);
FORCEPROP 1 LAST PACK_TYPE 0402
J 0
(-6550 4275);
DISPLAY 0.617021 (-6550 4275);
PAINT SKYBLUE (-6550 4275);
FORCEPROP 1 LASTPIN (-6550 4225) $PN 2
J 0
(-6588 4237);
DISPLAY 0.617021 (-6588 4237);
PAINT ORANGE (-6588 4237);
FORCEPROP 1 LAST LOCATION R7W6
J 0
(-6900 4275);
DISPLAY 0.617021 (-6900 4275);
PAINT AQUA (-6900 4275);
FORCEPROP 1 LAST VALUE 0.0
J 2
(-6675 4275);
DISPLAY 0.617021 (-6675 4275);
PAINT SKYBLUE (-6675 4275);
FORCEPROP 1 LAST MATERIAL CHIP
J 0
(-6800 4325);
DISPLAY 0.617021 (-6800 4325);
PAINT SKYBLUE (-6800 4325);
FORCEPROP 1 LASTPIN (-6750 4225) $PN 1
J 0
(-6738 4237);
DISPLAY 0.617021 (-6738 4237);
PAINT ORANGE (-6738 4237);
FORCEPROP 1 LAST WATTAGE 1/16W
J 2
(-6800 4325);
DISPLAY 0.617021 (-6800 4325);
PAINT SKYBLUE (-6800 4325);
FORCEPROP 0 LAST POP NOPOP
J 0
(-6425 4175);
DISPLAY 0.638298 (-6425 4175);
PAINT RED (-6425 4175);
FORCEPROP 2 LAST CDS_LOCATION R7W6
J 0
(-6700 4275);
DISPLAY 0.617021 (-6700 4275);
PAINT AQUA (-6700 4275);
DISPLAY INVISIBLE (-6700 4275);
FORCEPROP 1 LAST PATH I176
J 0
(-6700 4375);
DISPLAY 0.978723 (-6700 4375);
PAINT WHITE (-6700 4375);
DISPLAY INVISIBLE (-6700 4375);
FORCEPROP 2 LAST SEC_TYPE 0402
J 0
(-6700 4425);
DISPLAY 1.021277 (-6700 4425);
PAINT ORANGE (-6700 4425);
DISPLAY INVISIBLE (-6700 4425);
FORCEPROP 2 LAST BOM_COST SB
J 0
(-6700 4375);
DISPLAY 1.021277 (-6700 4375);
PAINT ORANGE (-6700 4375);
DISPLAY INVISIBLE (-6700 4375);
FORCEPROP 2 LAST ROOM SB
J 0
(-6700 4325);
DISPLAY 1.021277 (-6700 4325);
PAINT ORANGE (-6700 4325);
DISPLAY INVISIBLE (-6700 4325);
FORCEPROP 2 LAST CDS_LIB mstr_discrete
J 0
(-6650 4225);
PAINT ORANGE (-6650 4225);
DISPLAY INVISIBLE (-6650 4225);
FORCEPROP 2 LAST SEC 1
J 0
(-6700 4425);
DISPLAY 0.553191 (-6700 4425);
PAINT MONO (-6700 4425);
DISPLAY INVISIBLE (-6700 4425);
FORCEADD RES..1
(-6650 4375);
FORCEPROP 1 LASTPIN (-6550 4375) $PN 2
J 0
(-6588 4387);
DISPLAY 0.617021 (-6588 4387);
PAINT ORANGE (-6588 4387);
FORCEPROP 0 LAST POP NOPOP
J 0
(-6900 4375);
DISPLAY 0.638298 (-6900 4375);
PAINT RED (-6900 4375);
FORCEPROP 1 LAST VALUE 0.0
J 2
(-6675 4425);
DISPLAY 0.617021 (-6675 4425);
PAINT SKYBLUE (-6675 4425);
FORCEPROP 1 LAST WATTAGE 1/16W
J 2
(-6800 4475);
DISPLAY 0.617021 (-6800 4475);
PAINT SKYBLUE (-6800 4475);
FORCEPROP 1 LAST TOLERANCE 5%
J 0
(-6625 4425);
DISPLAY 0.617021 (-6625 4425);
PAINT SKYBLUE (-6625 4425);
FORCEPROP 1 LASTPIN (-6750 4375) $PN 1
J 0
(-6738 4387);
DISPLAY 0.617021 (-6738 4387);
PAINT ORANGE (-6738 4387);
FORCEPROP 1 LAST LOCATION R7W9
J 0
(-6900 4425);
DISPLAY 0.617021 (-6900 4425);
PAINT AQUA (-6900 4425);
FORCEPROP 1 LAST PACK_TYPE 0402
J 0
(-6550 4425);
DISPLAY 0.617021 (-6550 4425);
PAINT SKYBLUE (-6550 4425);
FORCEPROP 1 LAST MATERIAL CHIP
J 0
(-6800 4475);
DISPLAY 0.617021 (-6800 4475);
PAINT SKYBLUE (-6800 4475);
FORCEPROP 1 LAST PART_NUMBER G21497-005
J 0
(-6675 4475);
DISPLAY 0.617021 (-6675 4475);
PAINT BLUE (-6675 4475);
FORCEPROP 1 LAST PATH I177
J 0
(-6700 4525);
DISPLAY 0.978723 (-6700 4525);
PAINT WHITE (-6700 4525);
DISPLAY INVISIBLE (-6700 4525);
FORCEPROP 2 LAST SEC 1
J 0
(-6700 4575);
DISPLAY 0.553191 (-6700 4575);
PAINT MONO (-6700 4575);
DISPLAY INVISIBLE (-6700 4575);
FORCEPROP 2 LAST CDS_LIB mstr_discrete
J 0
(-6650 4375);
PAINT ORANGE (-6650 4375);
DISPLAY INVISIBLE (-6650 4375);
FORCEPROP 2 LAST ROOM SB
J 0
(-6700 4475);
DISPLAY 1.021277 (-6700 4475);
PAINT ORANGE (-6700 4475);
DISPLAY INVISIBLE (-6700 4475);
FORCEPROP 2 LAST BOM_COST SB
J 0
(-6700 4525);
DISPLAY 1.021277 (-6700 4525);
PAINT ORANGE (-6700 4525);
DISPLAY INVISIBLE (-6700 4525);
FORCEPROP 2 LAST SEC_TYPE 0402
J 0
(-6700 4575);
DISPLAY 1.021277 (-6700 4575);
PAINT ORANGE (-6700 4575);
DISPLAY INVISIBLE (-6700 4575);
FORCEPROP 2 LAST CDS_LOCATION R7W9
J 0
(-6700 4425);
DISPLAY 0.617021 (-6700 4425);
PAINT AQUA (-6700 4425);
DISPLAY INVISIBLE (-6700 4425);
FORCEADD CAP..1
(-7700 600);
FORCEPROP 1 LAST MATERIAL COG
J 0
(-7650 500);
DISPLAY 0.638298 (-7650 500);
PAINT SKYBLUE (-7650 500);
FORCEPROP 1 LAST PACK_TYPE 0402LF
J 0
(-7650 400);
DISPLAY 0.638298 (-7650 400);
PAINT SKYBLUE (-7650 400);
FORCEPROP 1 LAST TOLERANCE 5%
J 0
(-7650 550);
DISPLAY 0.638298 (-7650 550);
PAINT SKYBLUE (-7650 550);
FORCEPROP 1 LAST VOLTAGE 50V
J 0
(-7650 600);
DISPLAY 0.638298 (-7650 600);
PAINT SKYBLUE (-7650 600);
FORCEPROP 1 LAST LOCATION C8C1
J 0
(-7650 700);
DISPLAY 0.638298 (-7650 700);
PAINT SKYBLUE (-7650 700);
FORCEPROP 1 LASTPIN (-7700 700) $PN 1
J 0
(-7690 680);
DISPLAY 0.787234 (-7690 680);
PAINT ORANGE (-7690 680);
FORCEPROP 1 LASTPIN (-7700 500) $PN 2
J 0
(-7690 480);
DISPLAY 0.787234 (-7690 480);
PAINT ORANGE (-7690 480);
FORCEPROP 1 LAST VALUE 33.0PF
J 0
(-7650 650);
DISPLAY 0.638298 (-7650 650);
PAINT SKYBLUE (-7650 650);
FORCEPROP 1 LAST PART_NUMBER A36095-031
J 0
(-7650 450);
DISPLAY 0.638298 (-7650 450);
PAINT BLUE (-7650 450);
FORCEPROP 1 LAST PATH I178
J 0
(-7650 750);
DISPLAY 0.978723 (-7650 750);
PAINT WHITE (-7650 750);
DISPLAY INVISIBLE (-7650 750);
FORCEPROP 2 LAST SEC 1
J 0
(-7650 800);
DISPLAY 0.680851 (-7650 800);
PAINT MONO (-7650 800);
DISPLAY INVISIBLE (-7650 800);
FORCEPROP 2 LAST SEC_TYPE 0402LF
J 0
(-7650 800);
DISPLAY 1.021277 (-7650 800);
PAINT ORANGE (-7650 800);
DISPLAY INVISIBLE (-7650 800);
FORCEPROP 2 LAST CDS_LIB mstr_discrete
J 0
(-7700 600);
DISPLAY INVISIBLE (-7700 600);
FORCEADD CAP..1
(-7250 600);
FORCEPROP 1 LAST MATERIAL COG
J 0
(-7200 500);
DISPLAY 0.638298 (-7200 500);
PAINT SKYBLUE (-7200 500);
FORCEPROP 1 LAST PART_NUMBER A36095-031
J 0
(-7200 450);
DISPLAY 0.638298 (-7200 450);
PAINT BLUE (-7200 450);
FORCEPROP 1 LAST PACK_TYPE 0402LF
J 0
(-7200 400);
DISPLAY 0.638298 (-7200 400);
PAINT SKYBLUE (-7200 400);
FORCEPROP 1 LAST VOLTAGE 50V
J 0
(-7200 600);
DISPLAY 0.638298 (-7200 600);
PAINT SKYBLUE (-7200 600);
FORCEPROP 1 LAST VALUE 33.0PF
J 0
(-7200 650);
DISPLAY 0.638298 (-7200 650);
PAINT SKYBLUE (-7200 650);
FORCEPROP 1 LASTPIN (-7250 700) $PN 1
J 0
(-7240 680);
DISPLAY 0.787234 (-7240 680);
PAINT ORANGE (-7240 680);
FORCEPROP 1 LAST LOCATION C8C2
J 0
(-7200 700);
DISPLAY 0.638298 (-7200 700);
PAINT SKYBLUE (-7200 700);
FORCEPROP 1 LASTPIN (-7250 500) $PN 2
J 0
(-7240 480);
DISPLAY 0.787234 (-7240 480);
PAINT ORANGE (-7240 480);
FORCEPROP 1 LAST TOLERANCE 5%
J 0
(-7200 550);
DISPLAY 0.638298 (-7200 550);
PAINT SKYBLUE (-7200 550);
FORCEPROP 2 LAST SEC 1
J 0
(-7200 800);
DISPLAY 0.680851 (-7200 800);
PAINT MONO (-7200 800);
DISPLAY INVISIBLE (-7200 800);
FORCEPROP 2 LAST SEC_TYPE 0402LF
J 0
(-7200 800);
DISPLAY 1.021277 (-7200 800);
PAINT ORANGE (-7200 800);
DISPLAY INVISIBLE (-7200 800);
FORCEPROP 2 LAST CDS_LIB mstr_discrete
J 0
(-7250 600);
DISPLAY INVISIBLE (-7250 600);
FORCEPROP 1 LAST PATH I179
J 0
(-7200 750);
DISPLAY 0.978723 (-7200 750);
PAINT WHITE (-7200 750);
DISPLAY INVISIBLE (-7200 750);
FORCEADD RES..2
(-6450 4600);
FORCEPROP 1 LASTPIN (-6450 4700) $PN 1
J 0
(-6445 4662);
DISPLAY 0.617021 (-6445 4662);
PAINT ORANGE (-6445 4662);
FORCEPROP 1 LASTPIN (-6450 4500) $PN 2
J 0
(-6445 4510);
DISPLAY 0.617021 (-6445 4510);
PAINT ORANGE (-6445 4510);
FORCEPROP 1 LAST TOLERANCE 1%
J 0
(-6405 4625);
DISPLAY 0.617021 (-6405 4625);
PAINT SKYBLUE (-6405 4625);
FORCEPROP 1 LAST WATTAGE 1/16W
J 0
(-6410 4575);
DISPLAY 0.617021 (-6410 4575);
PAINT SKYBLUE (-6410 4575);
FORCEPROP 1 LAST PACK_TYPE 0402
J 0
(-6410 4425);
DISPLAY 0.617021 (-6410 4425);
PAINT SKYBLUE (-6410 4425);
FORCEPROP 1 LAST MATERIAL CHIP
J 0
(-6410 4525);
DISPLAY 0.617021 (-6410 4525);
PAINT SKYBLUE (-6410 4525);
FORCEPROP 1 LAST PART_NUMBER G21796-072
J 0
(-6410 4475);
DISPLAY 0.617021 (-6410 4475);
PAINT BLUE (-6410 4475);
FORCEPROP 1 LAST VALUE 4.75K
J 0
(-6405 4675);
DISPLAY 0.617021 (-6405 4675);
PAINT SKYBLUE (-6405 4675);
FORCEPROP 1 LAST LOCATION R7W19
J 0
(-6405 4725);
DISPLAY 0.617021 (-6405 4725);
PAINT AQUA (-6405 4725);
FORCEPROP 1 LAST PATH I180
J 0
(-6400 4775);
DISPLAY 0.978723 (-6400 4775);
PAINT WHITE (-6400 4775);
DISPLAY INVISIBLE (-6400 4775);
FORCEPROP 2 LAST CDS_LOCATION R7W19
J 0
(-6405 4725);
DISPLAY 0.617021 (-6405 4725);
PAINT AQUA (-6405 4725);
DISPLAY INVISIBLE (-6405 4725);
FORCEPROP 2 LAST CDS_LIB mstr_discrete
J 0
(-6450 4600);
PAINT ORANGE (-6450 4600);
DISPLAY INVISIBLE (-6450 4600);
FORCEPROP 2 LAST SEC_TYPE 0402
J 0
(-6400 4825);
DISPLAY 1.021277 (-6400 4825);
PAINT ORANGE (-6400 4825);
DISPLAY INVISIBLE (-6400 4825);
FORCEPROP 2 LAST SEC 1
J 0
(-6400 4825);
DISPLAY 0.680851 (-6400 4825);
PAINT MONO (-6400 4825);
DISPLAY INVISIBLE (-6400 4825);
FORCEPROP 0 LAST ROOM CPU0
J 0
(-6400 4825);
DISPLAY 1.021277 (-6400 4825);
PAINT ORANGE (-6400 4825);
DISPLAY INVISIBLE (-6400 4825);
FORCEADD P3V3_STBY..1
(-6450 4900);
FORCEPROP 3 LASTPIN (-6450 4850) SIG_NAME P3V3_STBY\g
J 0
(-6440 4860);
DISPLAY 0.659574 (-6440 4860);
PAINT MONO (-6440 4860);
DISPLAY INVISIBLE (-6440 4860);
FORCEPROP 1 LAST HDL_POWER P3V3_STBY
J 0
(-6750 4775);
DISPLAY 0.872340 (-6750 4775);
PAINT GREEN (-6750 4775);
DISPLAY INVISIBLE (-6750 4775);
FORCEPROP 1 LAST BODY_TYPE PLUMBING
J 0
(-6495 4857);
DISPLAY 0.340426 (-6495 4857);
PAINT GREEN (-6495 4857);
DISPLAY INVISIBLE (-6495 4857);
FORCEPROP 1 LAST SIZE 1B
J 0
(-6405 4922);
DISPLAY 0.340426 (-6405 4922);
PAINT GREEN (-6405 4922);
DISPLAY INVISIBLE (-6405 4922);
FORCEPROP 2 LAST CDS_LIB mstr_symbols
J 0
(-6450 4900);
PAINT ORANGE (-6450 4900);
DISPLAY INVISIBLE (-6450 4900);
FORCEPROP 1 LAST VOLTAGE 3.3V
J 0
(-6495 4857);
DISPLAY 0.340426 (-6495 4857);
PAINT SKYBLUE (-6495 4857);
DISPLAY INVISIBLE (-6495 4857);
FORCEPROP 1 LAST PATH I181
J 0
(-6405 4902);
DISPLAY 0.340426 (-6405 4902);
PAINT GREEN (-6405 4902);
DISPLAY INVISIBLE (-6405 4902);
FORCEADD RES..2
(-6200 4600);
FORCEPROP 1 LAST LOCATION R7W21
J 0
(-6155 4725);
DISPLAY 0.617021 (-6155 4725);
PAINT AQUA (-6155 4725);
FORCEPROP 1 LAST PART_NUMBER G21796-072
J 0
(-6160 4475);
DISPLAY 0.617021 (-6160 4475);
PAINT BLUE (-6160 4475);
FORCEPROP 1 LAST MATERIAL CHIP
J 0
(-6160 4525);
DISPLAY 0.617021 (-6160 4525);
PAINT SKYBLUE (-6160 4525);
FORCEPROP 1 LAST PACK_TYPE 0402
J 0
(-6160 4425);
DISPLAY 0.617021 (-6160 4425);
PAINT SKYBLUE (-6160 4425);
FORCEPROP 1 LAST WATTAGE 1/16W
J 0
(-6160 4575);
DISPLAY 0.617021 (-6160 4575);
PAINT SKYBLUE (-6160 4575);
FORCEPROP 1 LAST VALUE 4.75K
J 0
(-6155 4675);
DISPLAY 0.617021 (-6155 4675);
PAINT SKYBLUE (-6155 4675);
FORCEPROP 1 LAST TOLERANCE 1%
J 0
(-6155 4625);
DISPLAY 0.617021 (-6155 4625);
PAINT SKYBLUE (-6155 4625);
FORCEPROP 1 LASTPIN (-6200 4500) $PN 2
J 0
(-6195 4510);
DISPLAY 0.617021 (-6195 4510);
PAINT ORANGE (-6195 4510);
FORCEPROP 1 LASTPIN (-6200 4700) $PN 1
J 0
(-6195 4662);
DISPLAY 0.617021 (-6195 4662);
PAINT ORANGE (-6195 4662);
FORCEPROP 1 LAST PATH I183
J 0
(-6150 4775);
DISPLAY 0.978723 (-6150 4775);
PAINT WHITE (-6150 4775);
DISPLAY INVISIBLE (-6150 4775);
FORCEPROP 0 LAST ROOM CPU0
J 0
(-6150 4825);
DISPLAY 1.021277 (-6150 4825);
PAINT ORANGE (-6150 4825);
DISPLAY INVISIBLE (-6150 4825);
FORCEPROP 2 LAST SEC 1
J 0
(-6150 4825);
DISPLAY 0.680851 (-6150 4825);
PAINT MONO (-6150 4825);
DISPLAY INVISIBLE (-6150 4825);
FORCEPROP 2 LAST SEC_TYPE 0402
J 0
(-6150 4825);
DISPLAY 1.021277 (-6150 4825);
PAINT ORANGE (-6150 4825);
DISPLAY INVISIBLE (-6150 4825);
FORCEPROP 2 LAST CDS_LIB mstr_discrete
J 0
(-6200 4600);
PAINT ORANGE (-6200 4600);
DISPLAY INVISIBLE (-6200 4600);
FORCEPROP 2 LAST CDS_LOCATION R7W21
J 0
(-6155 4725);
DISPLAY 0.617021 (-6155 4725);
PAINT AQUA (-6155 4725);
DISPLAY INVISIBLE (-6155 4725);
FORCEADD OFFPAGE..5
(-5775 4425);
FORCEPROP 2 LAST PATH I19
J 0
(-5725 4500);
DISPLAY 1.021277 (-5725 4500);
PAINT ORANGE (-5725 4500);
DISPLAY INVISIBLE (-5725 4500);
FORCEPROP 2 LAST CDS_LIB mstr_standard
J 0
(-5775 4425);
PAINT ORANGE (-5775 4425);
DISPLAY INVISIBLE (-5775 4425);
FORCEPROP 1 LAST OFFPAGE TRUE
J 0
(-5450 4300);
PAINT GREEN (-5450 4300);
DISPLAY INVISIBLE (-5450 4300);
FORCEPROP 1 LAST COMMENT_BODY TRUE
J 0
(-5675 4350);
DISPLAY 1.404255 (-5675 4350);
PAINT PEACH (-5675 4350);
DISPLAY INVISIBLE (-5675 4350);
FORCEPROP 2 LAST $XR0 118 
J 0
(-6204 4425);
DISPLAY 0.638298 (-6204 4425);
PAINT MONO (-6204 4425);
DISPLAY INVISIBLE (-6204 4425);
FORCEADD OFFPAGE..5
(-5775 4125);
FORCEPROP 2 LAST $XR1 191 
J 0
(-6420 4125);
DISPLAY 0.638298 (-6420 4125);
PAINT MONO (-6420 4125);
FORCEPROP 2 LAST $XR0 148 
J 0
(-6300 4125);
DISPLAY 0.638298 (-6300 4125);
PAINT MONO (-6300 4125);
FORCEPROP 2 LAST CDS_LIB mstr_standard
J 0
(-5775 4125);
PAINT ORANGE (-5775 4125);
DISPLAY INVISIBLE (-5775 4125);
FORCEPROP 2 LAST PATH I25
J 0
(-6025 4175);
DISPLAY 1.021277 (-6025 4175);
PAINT ORANGE (-6025 4175);
DISPLAY INVISIBLE (-6025 4175);
FORCEPROP 1 LAST OFFPAGE TRUE
J 0
(-5450 4000);
PAINT GREEN (-5450 4000);
DISPLAY INVISIBLE (-5450 4000);
FORCEPROP 1 LAST COMMENT_BODY TRUE
J 0
(-5675 4050);
DISPLAY 1.404255 (-5675 4050);
PAINT PEACH (-5675 4050);
DISPLAY INVISIBLE (-5675 4050);
FORCEADD OFFPAGE..1
(-5775 4025);
FORCEPROP 2 LAST $XR1 191 
J 0
(-6147 4025);
DISPLAY 0.638298 (-6147 4025);
PAINT MONO (-6147 4025);
FORCEPROP 2 LAST $XR0 156 
J 0
(-6027 4025);
DISPLAY 0.638298 (-6027 4025);
PAINT MONO (-6027 4025);
FORCEPROP 2 LAST PATH I26
J 0
(-5725 4100);
DISPLAY 1.021277 (-5725 4100);
PAINT ORANGE (-5725 4100);
DISPLAY INVISIBLE (-5725 4100);
FORCEPROP 2 LAST CDS_LIB mstr_standard
J 0
(-5775 4025);
PAINT ORANGE (-5775 4025);
DISPLAY INVISIBLE (-5775 4025);
FORCEPROP 1 LAST OFFPAGE TRUE
J 0
(-5450 3900);
PAINT GREEN (-5450 3900);
DISPLAY INVISIBLE (-5450 3900);
FORCEPROP 1 LAST COMMENT_BODY TRUE
J 0
(-5650 3925);
DISPLAY 1.404255 (-5650 3925);
PAINT PEACH (-5650 3925);
DISPLAY INVISIBLE (-5650 3925);
FORCEADD OFFPAGE..1
(-5675 3175);
FORCEPROP 2 LAST $XR2 112 
J 0
(-6197 3175);
DISPLAY 0.638298 (-6197 3175);
PAINT MONO (-6197 3175);
FORCEPROP 2 LAST $XR1 254 
J 0
(-6077 3175);
DISPLAY 0.638298 (-6077 3175);
PAINT MONO (-6077 3175);
FORCEPROP 2 LAST $XR0 111 
J 0
(-5957 3175);
DISPLAY 0.638298 (-5957 3175);
PAINT MONO (-5957 3175);
FORCEPROP 2 LAST CDS_LIB mstr_standard
J 0
(-5675 3175);
PAINT ORANGE (-5675 3175);
DISPLAY INVISIBLE (-5675 3175);
FORCEPROP 2 LAST PATH I34
J 0
(-5925 3225);
DISPLAY 1.021277 (-5925 3225);
PAINT ORANGE (-5925 3225);
DISPLAY INVISIBLE (-5925 3225);
FORCEPROP 1 LAST OFFPAGE TRUE
J 0
(-5350 3050);
PAINT GREEN (-5350 3050);
DISPLAY INVISIBLE (-5350 3050);
FORCEPROP 1 LAST COMMENT_BODY TRUE
J 0
(-5550 3075);
DISPLAY 1.404255 (-5550 3075);
PAINT PEACH (-5550 3075);
DISPLAY INVISIBLE (-5550 3075);
FORCEADD OFFPAGE..6
(-5675 3125);
FORCEPROP 2 LAST $XR2 112 
J 0
(-6195 3125);
DISPLAY 0.638298 (-6195 3125);
PAINT MONO (-6195 3125);
FORCEPROP 2 LAST $XR1 254 
J 0
(-6075 3125);
DISPLAY 0.638298 (-6075 3125);
PAINT MONO (-6075 3125);
FORCEPROP 2 LAST $XR0 111 
J 0
(-5955 3125);
DISPLAY 0.638298 (-5955 3125);
PAINT MONO (-5955 3125);
FORCEPROP 2 LAST CDS_LIB mstr_standard
J 0
(-5675 3125);
PAINT ORANGE (-5675 3125);
DISPLAY INVISIBLE (-5675 3125);
FORCEPROP 2 LAST PATH I35
J 0
(-5950 3175);
DISPLAY 1.021277 (-5950 3175);
PAINT ORANGE (-5950 3175);
DISPLAY INVISIBLE (-5950 3175);
FORCEPROP 1 LAST OFFPAGE TRUE
J 0
(-5350 3000);
PAINT GREEN (-5350 3000);
DISPLAY INVISIBLE (-5350 3000);
FORCEPROP 1 LAST COMMENT_BODY TRUE
J 0
(-5575 3050);
DISPLAY 1.404255 (-5575 3050);
PAINT PEACH (-5575 3050);
DISPLAY INVISIBLE (-5575 3050);
FORCEADD OFFPAGE..6
(-5675 3075);
FORCEPROP 2 LAST $XR2 255 
J 0
(-6195 3075);
DISPLAY 0.638298 (-6195 3075);
PAINT MONO (-6195 3075);
FORCEPROP 2 LAST $XR1 111 
J 0
(-6075 3075);
DISPLAY 0.638298 (-6075 3075);
PAINT MONO (-6075 3075);
FORCEPROP 2 LAST $XR0 112 
J 0
(-5955 3075);
DISPLAY 0.638298 (-5955 3075);
PAINT MONO (-5955 3075);
FORCEPROP 2 LAST CDS_LIB mstr_standard
J 0
(-5675 3075);
PAINT ORANGE (-5675 3075);
DISPLAY INVISIBLE (-5675 3075);
FORCEPROP 2 LAST PATH I36
J 0
(-5950 3125);
DISPLAY 1.021277 (-5950 3125);
PAINT ORANGE (-5950 3125);
DISPLAY INVISIBLE (-5950 3125);
FORCEPROP 1 LAST OFFPAGE TRUE
J 0
(-5350 2950);
PAINT GREEN (-5350 2950);
DISPLAY INVISIBLE (-5350 2950);
FORCEPROP 1 LAST COMMENT_BODY TRUE
J 0
(-5575 3000);
DISPLAY 1.404255 (-5575 3000);
PAINT PEACH (-5575 3000);
DISPLAY INVISIBLE (-5575 3000);
FORCEADD OFFPAGE..6
(-5675 3025);
FORCEPROP 2 LAST $XR2 112 
J 0
(-6195 3025);
DISPLAY 0.638298 (-6195 3025);
PAINT MONO (-6195 3025);
FORCEPROP 2 LAST $XR1 254 
J 0
(-6075 3025);
DISPLAY 0.638298 (-6075 3025);
PAINT MONO (-6075 3025);
FORCEPROP 2 LAST $XR0 111 
J 0
(-5955 3025);
DISPLAY 0.638298 (-5955 3025);
PAINT MONO (-5955 3025);
FORCEPROP 2 LAST PATH I37
J 0
(-5950 3075);
DISPLAY 1.021277 (-5950 3075);
PAINT ORANGE (-5950 3075);
DISPLAY INVISIBLE (-5950 3075);
FORCEPROP 2 LAST CDS_LIB mstr_standard
J 0
(-5675 3025);
PAINT ORANGE (-5675 3025);
DISPLAY INVISIBLE (-5675 3025);
FORCEPROP 1 LAST OFFPAGE TRUE
J 0
(-5350 2900);
PAINT GREEN (-5350 2900);
DISPLAY INVISIBLE (-5350 2900);
FORCEPROP 1 LAST COMMENT_BODY TRUE
J 0
(-5575 2950);
DISPLAY 1.404255 (-5575 2950);
PAINT PEACH (-5575 2950);
DISPLAY INVISIBLE (-5575 2950);
FORCEADD OFFPAGE..5
(-5700 2975);
FORCEPROP 2 LAST $XR1 112 
J 0
(-6075 2975);
DISPLAY 0.638298 (-6075 2975);
PAINT MONO (-6075 2975);
FORCEPROP 2 LAST $XR0 111 
J 0
(-5955 2975);
DISPLAY 0.638298 (-5955 2975);
PAINT MONO (-5955 2975);
FORCEPROP 2 LAST CDS_LIB mstr_standard
J 0
(-5700 2975);
PAINT ORANGE (-5700 2975);
DISPLAY INVISIBLE (-5700 2975);
FORCEPROP 2 LAST PATH I38
J 0
(-5975 3025);
DISPLAY 1.021277 (-5975 3025);
PAINT ORANGE (-5975 3025);
DISPLAY INVISIBLE (-5975 3025);
FORCEPROP 1 LAST OFFPAGE TRUE
J 0
(-5375 2850);
PAINT GREEN (-5375 2850);
DISPLAY INVISIBLE (-5375 2850);
FORCEPROP 1 LAST COMMENT_BODY TRUE
J 0
(-5600 2900);
DISPLAY 1.404255 (-5600 2900);
PAINT PEACH (-5600 2900);
DISPLAY INVISIBLE (-5600 2900);
FORCEADD OFFPAGE..3
R 2
(-5675 2825);
FORCEPROP 2 LAST $XR2 255 
J 0
(-6195 2825);
DISPLAY 0.638298 (-6195 2825);
PAINT MONO (-6195 2825);
FORCEPROP 2 LAST $XR1 111 
J 0
(-6075 2825);
DISPLAY 0.638298 (-6075 2825);
PAINT MONO (-6075 2825);
FORCEPROP 2 LAST $XR0 112 
J 0
(-5955 2825);
DISPLAY 0.638298 (-5955 2825);
PAINT MONO (-5955 2825);
FORCEPROP 2 LAST PATH I40
J 2
(-5425 2875);
DISPLAY 1.021277 (-5425 2875);
PAINT ORANGE (-5425 2875);
DISPLAY INVISIBLE (-5425 2875);
FORCEPROP 2 LAST CDS_LIB mstr_standard
J 2
(-5675 2825);
PAINT ORANGE (-5675 2825);
DISPLAY INVISIBLE (-5675 2825);
FORCEPROP 1 LAST OFFPAGE TRUE
J 2
(-6000 2700);
DISPLAY 0.872340 (-6000 2700);
PAINT GREEN (-6000 2700);
DISPLAY INVISIBLE (-6000 2700);
FORCEPROP 1 LAST COMMENT_BODY TRUE
J 2
(-5625 2725);
DISPLAY 0.872340 (-5625 2725);
PAINT GREEN (-5625 2725);
DISPLAY INVISIBLE (-5625 2725);
FORCEADD OFFPAGE..4
(-1925 4175);
FORCEPROP 2 LAST $XR0 142 
J 0
(-1739 4175);
DISPLAY 0.638298 (-1739 4175);
PAINT MONO (-1739 4175);
FORCEPROP 2 LAST PATH I41
J 0
(-1750 4250);
DISPLAY 1.021277 (-1750 4250);
PAINT ORANGE (-1750 4250);
DISPLAY INVISIBLE (-1750 4250);
FORCEPROP 2 LAST CDS_LIB mstr_standard
J 0
(-1925 4175);
PAINT ORANGE (-1925 4175);
DISPLAY INVISIBLE (-1925 4175);
FORCEPROP 1 LAST OFFPAGE TRUE
J 0
(-1600 4050);
PAINT GREEN (-1600 4050);
DISPLAY INVISIBLE (-1600 4050);
FORCEPROP 1 LAST COMMENT_BODY TRUE
J 0
(-1950 4075);
DISPLAY 1.404255 (-1950 4075);
PAINT PEACH (-1950 4075);
DISPLAY INVISIBLE (-1950 4075);
FORCEADD OFFPAGE..2
(-1925 4125);
FORCEPROP 2 LAST $XR0 191 
J 0
(-1736 4125);
DISPLAY 0.638298 (-1736 4125);
PAINT MONO (-1736 4125);
FORCEPROP 2 LAST PATH I42
J 0
(-1750 4200);
DISPLAY 1.021277 (-1750 4200);
PAINT ORANGE (-1750 4200);
DISPLAY INVISIBLE (-1750 4200);
FORCEPROP 2 LAST CDS_LIB mstr_standard
J 0
(-1925 4125);
PAINT ORANGE (-1925 4125);
DISPLAY INVISIBLE (-1925 4125);
FORCEPROP 1 LAST OFFPAGE TRUE
J 0
(-1600 4000);
PAINT GREEN (-1600 4000);
DISPLAY INVISIBLE (-1600 4000);
FORCEPROP 1 LAST COMMENT_BODY TRUE
J 0
(-1970 4030);
DISPLAY 1.404255 (-1970 4030);
PAINT PEACH (-1970 4030);
DISPLAY INVISIBLE (-1970 4030);
FORCEADD OFFPAGE..4
(-1925 4025);
FORCEPROP 2 LAST $XR3 147 
J 0
(-1379 4025);
DISPLAY 0.638298 (-1379 4025);
PAINT MONO (-1379 4025);
FORCEPROP 2 LAST $XR2 111 
J 0
(-1499 4025);
DISPLAY 0.638298 (-1499 4025);
PAINT MONO (-1499 4025);
FORCEPROP 2 LAST $XR1 192 
J 0
(-1619 4025);
DISPLAY 0.638298 (-1619 4025);
PAINT MONO (-1619 4025);
FORCEPROP 2 LAST $XR0 190 
J 0
(-1739 4025);
DISPLAY 0.638298 (-1739 4025);
PAINT MONO (-1739 4025);
FORCEPROP 2 LAST PATH I44
J 0
(-1600 4075);
DISPLAY 1.021277 (-1600 4075);
PAINT ORANGE (-1600 4075);
DISPLAY INVISIBLE (-1600 4075);
FORCEPROP 2 LAST CDS_LIB mstr_standard
J 0
(-1925 4025);
PAINT ORANGE (-1925 4025);
DISPLAY INVISIBLE (-1925 4025);
FORCEPROP 1 LAST OFFPAGE TRUE
J 0
(-1600 3900);
PAINT GREEN (-1600 3900);
DISPLAY INVISIBLE (-1600 3900);
FORCEPROP 1 LAST COMMENT_BODY TRUE
J 0
(-1950 3925);
DISPLAY 1.404255 (-1950 3925);
PAINT PEACH (-1950 3925);
DISPLAY INVISIBLE (-1950 3925);
FORCEADD OFFPAGE..4
(-1925 3875);
FORCEPROP 2 LAST $XR1 191 
J 0
(-1619 3875);
DISPLAY 0.638298 (-1619 3875);
PAINT MONO (-1619 3875);
FORCEPROP 2 LAST $XR0 156 
J 0
(-1739 3875);
DISPLAY 0.638298 (-1739 3875);
PAINT MONO (-1739 3875);
FORCEPROP 2 LAST PATH I46
J 0
(-1750 3950);
DISPLAY 1.021277 (-1750 3950);
PAINT ORANGE (-1750 3950);
DISPLAY INVISIBLE (-1750 3950);
FORCEPROP 2 LAST CDS_LIB mstr_standard
J 0
(-1925 3875);
PAINT ORANGE (-1925 3875);
DISPLAY INVISIBLE (-1925 3875);
FORCEPROP 1 LAST OFFPAGE TRUE
J 0
(-1600 3750);
DISPLAY 0.872340 (-1600 3750);
PAINT GREEN (-1600 3750);
DISPLAY INVISIBLE (-1600 3750);
FORCEPROP 1 LAST COMMENT_BODY TRUE
J 0
(-1950 3775);
DISPLAY 0.872340 (-1950 3775);
PAINT GREEN (-1950 3775);
DISPLAY INVISIBLE (-1950 3775);
FORCEADD OFFPAGE..4
(-1925 4275);
FORCEPROP 2 LAST $XR3 247 
J 0
(-1379 4275);
DISPLAY 0.638298 (-1379 4275);
PAINT MONO (-1379 4275);
FORCEPROP 2 LAST $XR2 144 
J 0
(-1499 4275);
DISPLAY 0.638298 (-1499 4275);
PAINT MONO (-1499 4275);
FORCEPROP 2 LAST $XR1 191 
J 0
(-1619 4275);
DISPLAY 0.638298 (-1619 4275);
PAINT MONO (-1619 4275);
FORCEPROP 2 LAST $XR0 133 
J 0
(-1739 4275);
DISPLAY 0.638298 (-1739 4275);
PAINT MONO (-1739 4275);
FORCEPROP 2 LAST CDS_LIB mstr_standard
J 0
(-1925 4275);
PAINT ORANGE (-1925 4275);
DISPLAY INVISIBLE (-1925 4275);
FORCEPROP 2 LAST PATH I47
J 0
(-1375 4325);
DISPLAY 1.021277 (-1375 4325);
PAINT ORANGE (-1375 4325);
DISPLAY INVISIBLE (-1375 4325);
FORCEPROP 1 LAST OFFPAGE TRUE
J 0
(-1600 4150);
PAINT GREEN (-1600 4150);
DISPLAY INVISIBLE (-1600 4150);
FORCEPROP 1 LAST COMMENT_BODY TRUE
J 0
(-1950 4175);
DISPLAY 1.404255 (-1950 4175);
PAINT PEACH (-1950 4175);
DISPLAY INVISIBLE (-1950 4175);
FORCEADD OFFPAGE..2
(-1925 4425);
FORCEPROP 2 LAST $XR0 92 
J 0
(-1736 4425);
DISPLAY 0.638298 (-1736 4425);
PAINT MONO (-1736 4425);
FORCEPROP 2 LAST PATH I48
J 0
(-1750 4500);
DISPLAY 1.021277 (-1750 4500);
PAINT ORANGE (-1750 4500);
DISPLAY INVISIBLE (-1750 4500);
FORCEPROP 2 LAST CDS_LIB mstr_standard
J 0
(-1925 4425);
PAINT ORANGE (-1925 4425);
DISPLAY INVISIBLE (-1925 4425);
FORCEPROP 1 LAST OFFPAGE TRUE
J 0
(-1600 4300);
PAINT GREEN (-1600 4300);
DISPLAY INVISIBLE (-1600 4300);
FORCEPROP 1 LAST COMMENT_BODY TRUE
J 0
(-1970 4330);
DISPLAY 1.404255 (-1970 4330);
PAINT PEACH (-1970 4330);
DISPLAY INVISIBLE (-1970 4330);
FORCEADD OFFPAGE..4
(-1925 4375);
FORCEPROP 2 LAST $XR4 247 
J 0
(-1259 4375);
DISPLAY 0.638298 (-1259 4375);
PAINT MONO (-1259 4375);
FORCEPROP 2 LAST $XR3 191 
J 0
(-1379 4375);
DISPLAY 0.638298 (-1379 4375);
PAINT MONO (-1379 4375);
FORCEPROP 2 LAST $XR2 157 
J 0
(-1499 4375);
DISPLAY 0.638298 (-1499 4375);
PAINT MONO (-1499 4375);
FORCEPROP 2 LAST $XR1 200 
J 0
(-1619 4375);
DISPLAY 0.638298 (-1619 4375);
PAINT MONO (-1619 4375);
FORCEPROP 2 LAST $XR0 196 
J 0
(-1739 4375);
DISPLAY 0.638298 (-1739 4375);
PAINT MONO (-1739 4375);
FORCEPROP 2 LAST PATH I49
J 0
(-1750 4450);
DISPLAY 1.021277 (-1750 4450);
PAINT ORANGE (-1750 4450);
DISPLAY INVISIBLE (-1750 4450);
FORCEPROP 2 LAST CDS_LIB mstr_standard
J 0
(-1925 4375);
PAINT ORANGE (-1925 4375);
DISPLAY INVISIBLE (-1925 4375);
FORCEPROP 1 LAST OFFPAGE TRUE
J 0
(-1600 4250);
PAINT GREEN (-1600 4250);
DISPLAY INVISIBLE (-1600 4250);
FORCEPROP 1 LAST COMMENT_BODY TRUE
J 0
(-1950 4275);
DISPLAY 1.404255 (-1950 4275);
PAINT PEACH (-1950 4275);
DISPLAY INVISIBLE (-1950 4275);
FORCEADD OFFPAGE..4
(-1925 4325);
FORCEPROP 2 LAST $XR2 144 
J 0
(-1499 4325);
DISPLAY 0.638298 (-1499 4325);
PAINT MONO (-1499 4325);
FORCEPROP 2 LAST $XR1 191 
J 0
(-1619 4325);
DISPLAY 0.638298 (-1619 4325);
PAINT MONO (-1619 4325);
FORCEPROP 2 LAST $XR0 133 
J 0
(-1739 4325);
DISPLAY 0.638298 (-1739 4325);
PAINT MONO (-1739 4325);
FORCEPROP 2 LAST PATH I50
J 0
(-1250 4375);
DISPLAY 1.021277 (-1250 4375);
PAINT ORANGE (-1250 4375);
DISPLAY INVISIBLE (-1250 4375);
FORCEPROP 2 LAST CDS_LIB mstr_standard
J 0
(-1925 4325);
PAINT ORANGE (-1925 4325);
DISPLAY INVISIBLE (-1925 4325);
FORCEPROP 1 LAST OFFPAGE TRUE
J 0
(-1600 4200);
PAINT GREEN (-1600 4200);
DISPLAY INVISIBLE (-1600 4200);
FORCEPROP 1 LAST COMMENT_BODY TRUE
J 0
(-1950 4225);
DISPLAY 1.404255 (-1950 4225);
PAINT PEACH (-1950 4225);
DISPLAY INVISIBLE (-1950 4225);
FORCEADD OFFPAGE..4
(-1925 2825);
FORCEPROP 2 LAST $XR0 134 
J 0
(-1739 2825);
DISPLAY 0.638298 (-1739 2825);
PAINT MONO (-1739 2825);
FORCEPROP 2 LAST PATH I53
J 0
(-1725 2875);
DISPLAY 1.021277 (-1725 2875);
PAINT ORANGE (-1725 2875);
DISPLAY INVISIBLE (-1725 2875);
FORCEPROP 2 LAST CDS_LIB mstr_standard
J 0
(-1925 2825);
PAINT ORANGE (-1925 2825);
DISPLAY INVISIBLE (-1925 2825);
FORCEPROP 1 LAST OFFPAGE TRUE
J 0
(-1600 2700);
PAINT GREEN (-1600 2700);
DISPLAY INVISIBLE (-1600 2700);
FORCEPROP 1 LAST COMMENT_BODY TRUE
J 0
(-1950 2725);
DISPLAY 1.404255 (-1950 2725);
PAINT PEACH (-1950 2725);
DISPLAY INVISIBLE (-1950 2725);
FORCEADD OFFPAGE..2
(-1925 2775);
FORCEPROP 2 LAST $XR0 166 
J 0
(-1736 2775);
DISPLAY 0.638298 (-1736 2775);
PAINT MONO (-1736 2775);
FORCEPROP 2 LAST PATH I54
J 0
(-1725 2825);
DISPLAY 1.021277 (-1725 2825);
PAINT ORANGE (-1725 2825);
DISPLAY INVISIBLE (-1725 2825);
FORCEPROP 2 LAST CDS_LIB mstr_standard
J 0
(-1925 2775);
PAINT ORANGE (-1925 2775);
DISPLAY INVISIBLE (-1925 2775);
FORCEPROP 1 LAST OFFPAGE TRUE
J 0
(-1600 2650);
PAINT GREEN (-1600 2650);
DISPLAY INVISIBLE (-1600 2650);
FORCEPROP 1 LAST COMMENT_BODY TRUE
J 0
(-1970 2680);
DISPLAY 1.404255 (-1970 2680);
PAINT PEACH (-1970 2680);
DISPLAY INVISIBLE (-1970 2680);
FORCEADD OFFPAGE..5
(-5675 2725);
FORCEPROP 2 LAST $XR0 111 
J 0
(-5930 2725);
DISPLAY 0.638298 (-5930 2725);
PAINT MONO (-5930 2725);
FORCEPROP 2 LAST PATH I55
J 0
(-5625 2800);
DISPLAY 1.021277 (-5625 2800);
PAINT ORANGE (-5625 2800);
DISPLAY INVISIBLE (-5625 2800);
FORCEPROP 2 LAST CDS_LIB mstr_standard
J 0
(-5675 2725);
PAINT ORANGE (-5675 2725);
DISPLAY INVISIBLE (-5675 2725);
FORCEPROP 1 LAST OFFPAGE TRUE
J 0
(-5350 2600);
PAINT GREEN (-5350 2600);
DISPLAY INVISIBLE (-5350 2600);
FORCEPROP 1 LAST COMMENT_BODY TRUE
J 0
(-5575 2650);
DISPLAY 1.404255 (-5575 2650);
PAINT PEACH (-5575 2650);
DISPLAY INVISIBLE (-5575 2650);
FORCEADD OFFPAGE..2
R 2
(-5675 2675);
FORCEPROP 2 LAST $XR2 112 
J 0
(-6170 2675);
DISPLAY 0.638298 (-6170 2675);
PAINT MONO (-6170 2675);
FORCEPROP 2 LAST $XR1 254 
J 0
(-6050 2675);
DISPLAY 0.638298 (-6050 2675);
PAINT MONO (-6050 2675);
FORCEPROP 2 LAST $XR0 111 
J 0
(-5930 2675);
DISPLAY 0.638298 (-5930 2675);
PAINT MONO (-5930 2675);
FORCEPROP 2 LAST CDS_LIB mstr_standard
J 2
(-5675 2675);
PAINT ORANGE (-5675 2675);
DISPLAY INVISIBLE (-5675 2675);
FORCEPROP 2 LAST PATH I56
J 2
(-5725 2750);
DISPLAY 1.021277 (-5725 2750);
PAINT ORANGE (-5725 2750);
DISPLAY INVISIBLE (-5725 2750);
FORCEPROP 1 LAST OFFPAGE TRUE
J 2
(-6000 2550);
DISPLAY 0.872340 (-6000 2550);
PAINT GREEN (-6000 2550);
DISPLAY INVISIBLE (-6000 2550);
FORCEPROP 1 LAST COMMENT_BODY TRUE
J 2
(-5630 2580);
DISPLAY 0.872340 (-5630 2580);
PAINT GREEN (-5630 2580);
DISPLAY INVISIBLE (-5630 2580);
FORCEADD RES..1
(-1575 2675);
FORCEPROP 1 LAST TOLERANCE 1%
J 0
(-1575 2625);
DISPLAY 0.617021 (-1575 2625);
PAINT SKYBLUE (-1575 2625);
FORCEPROP 1 LASTPIN (-1675 2675) $PN 1
J 0
(-1663 2687);
DISPLAY 0.617021 (-1663 2687);
PAINT ORANGE (-1663 2687);
FORCEPROP 1 LAST LOCATION R3N9
J 0
(-1625 2725);
DISPLAY 0.617021 (-1625 2725);
PAINT AQUA (-1625 2725);
FORCEPROP 1 LASTPIN (-1475 2675) $PN 2
J 0
(-1513 2687);
DISPLAY 0.617021 (-1513 2687);
PAINT ORANGE (-1513 2687);
FORCEPROP 1 LAST PACK_TYPE 0402
J 0
(-1450 2625);
DISPLAY 0.617021 (-1450 2625);
PAINT SKYBLUE (-1450 2625);
FORCEPROP 1 LAST MATERIAL CHIP
J 0
(-1550 2575);
DISPLAY 0.617021 (-1550 2575);
PAINT SKYBLUE (-1550 2575);
FORCEPROP 1 LAST VALUE 10.0
J 2
(-1600 2625);
DISPLAY 0.617021 (-1600 2625);
PAINT SKYBLUE (-1600 2625);
FORCEPROP 1 LAST WATTAGE 1/16W
J 2
(-1575 2575);
DISPLAY 0.617021 (-1575 2575);
PAINT SKYBLUE (-1575 2575);
FORCEPROP 1 LAST PART_NUMBER G21796-066
J 0
(-1650 2525);
DISPLAY 0.617021 (-1650 2525);
PAINT BLUE (-1650 2525);
FORCEPROP 2 LAST SEC_TYPE 0402
J 0
(-1625 2875);
DISPLAY 1.021277 (-1625 2875);
PAINT ORANGE (-1625 2875);
DISPLAY INVISIBLE (-1625 2875);
FORCEPROP 0 LAST BOM_COST SB
J 0
(-1625 2975);
DISPLAY 1.021277 (-1625 2975);
PAINT ORANGE (-1625 2975);
DISPLAY INVISIBLE (-1625 2975);
FORCEPROP 2 LAST SEC 1
J 0
(-1625 2875);
DISPLAY 0.680851 (-1625 2875);
PAINT MONO (-1625 2875);
DISPLAY INVISIBLE (-1625 2875);
FORCEPROP 0 LAST ROOM SB
J 0
(-1625 2875);
DISPLAY 1.021277 (-1625 2875);
PAINT ORANGE (-1625 2875);
DISPLAY INVISIBLE (-1625 2875);
FORCEPROP 1 LAST PATH I66
J 0
(-1625 2825);
DISPLAY 0.978723 (-1625 2825);
PAINT WHITE (-1625 2825);
DISPLAY INVISIBLE (-1625 2825);
FORCEPROP 2 LAST CDS_LIB mstr_discrete
J 0
(-1575 2675);
PAINT ORANGE (-1575 2675);
DISPLAY INVISIBLE (-1575 2675);
FORCEPROP 2 LAST CDS_LOCATION R3N9
J 0
(-1625 2725);
DISPLAY 0.617021 (-1625 2725);
PAINT AQUA (-1625 2725);
DISPLAY INVISIBLE (-1625 2725);
FORCEADD RES..2
(-1075 2475);
FORCEPROP 1 LAST LOCATION R3N14
J 0
(-1030 2600);
DISPLAY 0.617021 (-1030 2600);
PAINT AQUA (-1030 2600);
FORCEPROP 1 LAST TOLERANCE 1%
J 0
(-1030 2500);
DISPLAY 0.617021 (-1030 2500);
PAINT SKYBLUE (-1030 2500);
FORCEPROP 1 LASTPIN (-1075 2375) $PN 2
J 0
(-1070 2385);
DISPLAY 0.617021 (-1070 2385);
PAINT ORANGE (-1070 2385);
FORCEPROP 1 LASTPIN (-1075 2575) $PN 1
J 0
(-1070 2537);
DISPLAY 0.617021 (-1070 2537);
PAINT ORANGE (-1070 2537);
FORCEPROP 1 LAST VALUE 49.9
J 0
(-1030 2550);
DISPLAY 0.617021 (-1030 2550);
PAINT SKYBLUE (-1030 2550);
FORCEPROP 1 LAST WATTAGE 1/16W
J 0
(-1035 2450);
DISPLAY 0.617021 (-1035 2450);
PAINT SKYBLUE (-1035 2450);
FORCEPROP 1 LAST MATERIAL EMPTY
J 0
(-1035 2400);
DISPLAY 0.617021 (-1035 2400);
PAINT RED (-1035 2400);
FORCEPROP 1 LAST PART_NUMBER G21796-047
J 0
(-1035 2350);
DISPLAY 0.617021 (-1035 2350);
PAINT BLUE (-1035 2350);
FORCEPROP 1 LAST PACK_TYPE 0402
J 0
(-1035 2300);
DISPLAY 0.617021 (-1035 2300);
PAINT SKYBLUE (-1035 2300);
FORCEPROP 2 LAST SEC 1
J 0
(-1025 2700);
DISPLAY 0.680851 (-1025 2700);
PAINT MONO (-1025 2700);
DISPLAY INVISIBLE (-1025 2700);
FORCEPROP 0 LAST BOM_COST SB
J 0
(-1025 2700);
DISPLAY 1.021277 (-1025 2700);
PAINT ORANGE (-1025 2700);
DISPLAY INVISIBLE (-1025 2700);
FORCEPROP 2 LAST SEC_TYPE 0402
J 0
(-1025 2700);
DISPLAY 1.021277 (-1025 2700);
PAINT ORANGE (-1025 2700);
DISPLAY INVISIBLE (-1025 2700);
FORCEPROP 1 LAST PATH I67
J 0
(-1025 2650);
DISPLAY 0.978723 (-1025 2650);
PAINT WHITE (-1025 2650);
DISPLAY INVISIBLE (-1025 2650);
FORCEPROP 0 LAST ROOM SB
J 0
(-1025 2650);
DISPLAY 1.021277 (-1025 2650);
PAINT ORANGE (-1025 2650);
DISPLAY INVISIBLE (-1025 2650);
FORCEPROP 2 LAST CDS_LOCATION R3N14
J 0
(-1030 2600);
DISPLAY 0.617021 (-1030 2600);
PAINT AQUA (-1030 2600);
DISPLAY INVISIBLE (-1030 2600);
FORCEPROP 2 LAST CDS_LIB mstr_discrete
J 0
(-1075 2475);
PAINT ORANGE (-1075 2475);
DISPLAY INVISIBLE (-1075 2475);
FORCEADD OFFPAGE..2
(-600 2675);
FORCEPROP 2 LAST $XR1 55 
J 0
(-321 2675);
DISPLAY 0.638298 (-321 2675);
PAINT MONO (-321 2675);
FORCEPROP 2 LAST $XR0 21 
J 0
(-411 2675);
DISPLAY 0.638298 (-411 2675);
PAINT MONO (-411 2675);
FORCEPROP 2 LAST PATH I68
J 0
(-425 2750);
DISPLAY 1.021277 (-425 2750);
PAINT ORANGE (-425 2750);
DISPLAY INVISIBLE (-425 2750);
FORCEPROP 2 LAST CDS_LIB mstr_standard
J 0
(-600 2675);
PAINT ORANGE (-600 2675);
DISPLAY INVISIBLE (-600 2675);
FORCEPROP 1 LAST OFFPAGE TRUE
J 0
(-275 2550);
DISPLAY 0.872340 (-275 2550);
PAINT GREEN (-275 2550);
DISPLAY INVISIBLE (-275 2550);
FORCEPROP 1 LAST COMMENT_BODY TRUE
J 0
(-645 2580);
DISPLAY 0.872340 (-645 2580);
PAINT GREEN (-645 2580);
DISPLAY INVISIBLE (-645 2580);
FORCEADD GND..1
(-1075 2225);
FORCEPROP 3 LASTPIN (-1075 2275) SIG_NAME GND\g
J 0
(-1065 2285);
DISPLAY 0.659574 (-1065 2285);
PAINT MONO (-1065 2285);
DISPLAY INVISIBLE (-1065 2285);
FORCEPROP 1 LAST SIZE 1B
J 0
(-1000 2175);
DISPLAY 0.872340 (-1000 2175);
PAINT AQUA (-1000 2175);
DISPLAY INVISIBLE (-1000 2175);
FORCEPROP 1 LAST PATH I69
J 0
(-1000 2225);
DISPLAY 0.872340 (-1000 2225);
PAINT AQUA (-1000 2225);
DISPLAY INVISIBLE (-1000 2225);
FORCEPROP 1 LAST VOLTAGE 0.0V
J 0
(-1120 2182);
DISPLAY 0.340426 (-1120 2182);
PAINT SKYBLUE (-1120 2182);
DISPLAY INVISIBLE (-1120 2182);
FORCEPROP 2 LAST CDS_LIB mstr_symbols
J 0
(-1075 2225);
PAINT ORANGE (-1075 2225);
DISPLAY INVISIBLE (-1075 2225);
FORCEPROP 1 LAST BODY_TYPE PLUMBING
J 0
(-1120 2182);
DISPLAY 0.340426 (-1120 2182);
PAINT GREEN (-1120 2182);
DISPLAY INVISIBLE (-1120 2182);
FORCEPROP 1 LAST HDL_POWER GND
J 0
(-1075 2375);
DISPLAY 0.872340 (-1075 2375);
PAINT GREEN (-1075 2375);
DISPLAY INVISIBLE (-1075 2375);
FORCEADD RES..2
(-2300 4650);
FORCEPROP 1 LAST VALUE 4.75K
J 0
(-2255 4725);
DISPLAY 0.617021 (-2255 4725);
PAINT SKYBLUE (-2255 4725);
FORCEPROP 1 LAST LOCATION R3N13
J 0
(-2255 4775);
DISPLAY 0.617021 (-2255 4775);
PAINT AQUA (-2255 4775);
FORCEPROP 1 LASTPIN (-2300 4750) $PN 1
J 0
(-2295 4712);
DISPLAY 0.617021 (-2295 4712);
PAINT ORANGE (-2295 4712);
FORCEPROP 1 LAST TOLERANCE 1%
J 0
(-2255 4675);
DISPLAY 0.617021 (-2255 4675);
PAINT SKYBLUE (-2255 4675);
FORCEPROP 1 LASTPIN (-2300 4550) $PN 2
J 0
(-2295 4560);
DISPLAY 0.617021 (-2295 4560);
PAINT ORANGE (-2295 4560);
FORCEPROP 1 LAST WATTAGE 1/16W
J 0
(-2260 4625);
DISPLAY 0.617021 (-2260 4625);
PAINT SKYBLUE (-2260 4625);
FORCEPROP 1 LAST MATERIAL CHIP
J 0
(-2260 4575);
DISPLAY 0.617021 (-2260 4575);
PAINT SKYBLUE (-2260 4575);
FORCEPROP 1 LAST PACK_TYPE 0402
J 0
(-2260 4475);
DISPLAY 0.617021 (-2260 4475);
PAINT SKYBLUE (-2260 4475);
FORCEPROP 1 LAST PART_NUMBER G21796-072
J 0
(-2260 4525);
DISPLAY 0.617021 (-2260 4525);
PAINT BLUE (-2260 4525);
FORCEPROP 2 LAST SEC_TYPE 0402
J 0
(-2250 4875);
DISPLAY 1.021277 (-2250 4875);
PAINT ORANGE (-2250 4875);
DISPLAY INVISIBLE (-2250 4875);
FORCEPROP 0 LAST BOM_COST SB
J 0
(-2250 4875);
DISPLAY 1.021277 (-2250 4875);
PAINT ORANGE (-2250 4875);
DISPLAY INVISIBLE (-2250 4875);
FORCEPROP 2 LAST SEC 1
J 0
(-2250 4875);
DISPLAY 0.680851 (-2250 4875);
PAINT MONO (-2250 4875);
DISPLAY INVISIBLE (-2250 4875);
FORCEPROP 0 LAST ROOM SB
J 0
(-2250 4825);
DISPLAY 1.021277 (-2250 4825);
PAINT ORANGE (-2250 4825);
DISPLAY INVISIBLE (-2250 4825);
FORCEPROP 1 LAST PATH I71
J 0
(-2250 4825);
DISPLAY 0.978723 (-2250 4825);
PAINT WHITE (-2250 4825);
DISPLAY INVISIBLE (-2250 4825);
FORCEPROP 2 LAST CDS_LIB mstr_discrete
J 0
(-2300 4650);
PAINT ORANGE (-2300 4650);
DISPLAY INVISIBLE (-2300 4650);
FORCEPROP 2 LAST CDS_LOCATION R3N13
J 0
(-2255 4775);
DISPLAY 0.617021 (-2255 4775);
PAINT AQUA (-2255 4775);
DISPLAY INVISIBLE (-2255 4775);
FORCEADD P3V3_STBY..1
(-2300 4875);
FORCEPROP 3 LASTPIN (-2300 4825) SIG_NAME P3V3_STBY\g
J 0
(-2290 4835);
DISPLAY 0.659574 (-2290 4835);
PAINT MONO (-2290 4835);
DISPLAY INVISIBLE (-2290 4835);
FORCEPROP 1 LAST PATH I72
J 0
(-2255 4877);
DISPLAY 0.340426 (-2255 4877);
PAINT GREEN (-2255 4877);
DISPLAY INVISIBLE (-2255 4877);
FORCEPROP 2 LAST CDS_LIB mstr_symbols
J 0
(-2300 4875);
PAINT ORANGE (-2300 4875);
DISPLAY INVISIBLE (-2300 4875);
FORCEPROP 1 LAST SIZE 1B
J 0
(-2255 4897);
DISPLAY 0.340426 (-2255 4897);
PAINT GREEN (-2255 4897);
DISPLAY INVISIBLE (-2255 4897);
FORCEPROP 1 LAST VOLTAGE 3.3V
J 0
(-2345 4832);
DISPLAY 0.340426 (-2345 4832);
PAINT SKYBLUE (-2345 4832);
DISPLAY INVISIBLE (-2345 4832);
FORCEPROP 1 LAST BODY_TYPE PLUMBING
J 0
(-2345 4832);
DISPLAY 0.340426 (-2345 4832);
PAINT GREEN (-2345 4832);
DISPLAY INVISIBLE (-2345 4832);
FORCEPROP 1 LAST HDL_POWER P3V3_STBY
J 0
(-2600 4750);
DISPLAY 0.872340 (-2600 4750);
PAINT ORANGE (-2600 4750);
DISPLAY INVISIBLE (-2600 4750);
FORCEADD LBG_CORE_QAT_EXT_D..5
(-4025 3025);
FORCEPROP 2 LASTPIN (-4925 3275) $PN R13
J 2
(-4935 3285);
DISPLAY 0.617021 (-4935 3285);
PAINT ORANGE (-4935 3285);
FORCEPROP 2 LASTPIN (-4925 3175) $PN AL56
J 2
(-4935 3185);
DISPLAY 0.617021 (-4935 3185);
PAINT ORANGE (-4935 3185);
FORCEPROP 2 LASTPIN (-4925 3975) $PN M11
J 2
(-4935 3985);
DISPLAY 0.617021 (-4935 3985);
PAINT ORANGE (-4935 3985);
FORCEPROP 2 LASTPIN (-4925 4025) $PN C15
J 2
(-4935 4035);
DISPLAY 0.617021 (-4935 4035);
PAINT ORANGE (-4935 4035);
FORCEPROP 2 LASTPIN (-4925 4125) $PN B16
J 2
(-4935 4135);
DISPLAY 0.617021 (-4935 4135);
PAINT ORANGE (-4935 4135);
FORCEPROP 2 LASTPIN (-4925 4375) $PN B14
J 2
(-4935 4385);
DISPLAY 0.617021 (-4935 4385);
PAINT ORANGE (-4935 4385);
FORCEPROP 2 LASTPIN (-4925 4225) $PN H9
J 2
(-4935 4235);
DISPLAY 0.617021 (-4935 4235);
PAINT ORANGE (-4935 4235);
FORCEPROP 2 LASTPIN (-4925 4325) $PN A15
J 2
(-4935 4335);
DISPLAY 0.617021 (-4935 4335);
PAINT ORANGE (-4935 4335);
FORCEPROP 2 LASTPIN (-4925 4275) $PN C13
J 2
(-4935 4285);
DISPLAY 0.617021 (-4935 4285);
PAINT ORANGE (-4935 4285);
FORCEPROP 1 LAST MATERIAL IC
J 0
(-4875 4625);
DISPLAY 0.617021 (-4875 4625);
PAINT SKYBLUE (-4875 4625);
FORCEPROP 2 LASTPIN (-4925 2475) $PN BH35
J 2
(-4935 2485);
DISPLAY 0.617021 (-4935 2485);
PAINT ORANGE (-4935 2485);
FORCEPROP 2 LASTPIN (-4925 2125) $PN BF31
J 2
(-4935 2135);
DISPLAY 0.617021 (-4935 2135);
PAINT ORANGE (-4935 2135);
FORCEPROP 2 LASTPIN (-3125 2325) $PN BM35
J 0
(-3115 2335);
DISPLAY 0.617021 (-3115 2335);
PAINT ORANGE (-3115 2335);
FORCEPROP 2 LASTPIN (-3125 2125) $PN BR27
J 0
(-3115 2135);
DISPLAY 0.617021 (-3115 2135);
PAINT ORANGE (-3115 2135);
FORCEPROP 2 LASTPIN (-4925 2175) $PN BG29
J 2
(-4935 2185);
DISPLAY 0.617021 (-4935 2185);
PAINT ORANGE (-4935 2185);
FORCEPROP 2 LASTPIN (-3125 4325) $PN R17
J 0
(-3115 4335);
DISPLAY 0.617021 (-3115 4335);
PAINT ORANGE (-3115 4335);
FORCEPROP 2 LASTPIN (-3125 4125) $PN P7
J 0
(-3115 4135);
DISPLAY 0.617021 (-3115 4135);
PAINT ORANGE (-3115 4135);
FORCEPROP 2 LASTPIN (-3125 4075) $PN M15
J 0
(-3115 4085);
DISPLAY 0.617021 (-3115 4085);
PAINT ORANGE (-3115 4085);
FORCEPROP 2 LASTPIN (-4925 1875) $PN BB29
J 2
(-4935 1885);
DISPLAY 0.617021 (-4935 1885);
PAINT ORANGE (-4935 1885);
FORCEPROP 1 LAST PART_NUMBER H91415-002
J 0
(-4875 1425);
DISPLAY 0.617021 (-4875 1425);
PAINT BLUE (-4875 1425);
FORCEPROP 2 LASTPIN (-4925 1775) $PN BL29
J 2
(-4935 1785);
DISPLAY 0.617021 (-4935 1785);
PAINT ORANGE (-4935 1785);
FORCEPROP 2 LASTPIN (-3125 4425) $PN R9
J 0
(-3115 4435);
DISPLAY 0.617021 (-3115 4435);
PAINT ORANGE (-3115 4435);
FORCEPROP 2 LASTPIN (-3125 4275) $PN BY19
J 0
(-3115 4285);
DISPLAY 0.617021 (-3115 4285);
PAINT ORANGE (-3115 4285);
FORCEPROP 2 LASTPIN (-3125 2375) $PN BR35
J 0
(-3115 2385);
DISPLAY 0.617021 (-3115 2385);
PAINT ORANGE (-3115 2385);
FORCEPROP 2 LASTPIN (-3125 2775) $PN U9
J 0
(-3115 2785);
DISPLAY 0.617021 (-3115 2785);
PAINT ORANGE (-3115 2785);
FORCEPROP 2 LASTPIN (-3125 3925) $PN U17
J 0
(-3115 3935);
DISPLAY 0.617021 (-3115 3935);
PAINT ORANGE (-3115 3935);
FORCEPROP 2 LASTPIN (-3125 4025) $PN P15
J 0
(-3115 4035);
DISPLAY 0.617021 (-3115 4035);
PAINT ORANGE (-3115 4035);
FORCEPROP 2 LASTPIN (-3125 2925) $PN R24
J 0
(-3115 2935);
DISPLAY 0.617021 (-3115 2935);
PAINT ORANGE (-3115 2935);
FORCEPROP 2 LASTPIN (-3125 2975) $PN P26
J 0
(-3115 2985);
DISPLAY 0.617021 (-3115 2985);
PAINT ORANGE (-3115 2985);
FORCEPROP 2 LASTPIN (-3125 1875) $PN BD42
J 0
(-3115 1885);
DISPLAY 0.617021 (-3115 1885);
PAINT ORANGE (-3115 1885);
FORCEPROP 2 LASTPIN (-3125 1775) $PN BG40
J 0
(-3115 1785);
DISPLAY 0.617021 (-3115 1785);
PAINT ORANGE (-3115 1785);
FORCEPROP 2 LASTPIN (-3125 1725) $PN BJ40
J 0
(-3115 1735);
DISPLAY 0.617021 (-3115 1735);
PAINT ORANGE (-3115 1735);
FORCEPROP 2 LASTPIN (-4925 3925) $PN H13
J 2
(-4935 3935);
DISPLAY 0.617021 (-4935 3935);
PAINT ORANGE (-4935 3935);
FORCEPROP 2 LASTPIN (-4925 3575) $PN V56
J 2
(-4935 3585);
DISPLAY 0.617021 (-4935 3585);
PAINT ORANGE (-4935 3585);
FORCEPROP 2 LASTPIN (-4925 3525) $PN Y56
J 2
(-4935 3535);
DISPLAY 0.617021 (-4935 3535);
PAINT ORANGE (-4935 3535);
FORCEPROP 2 LASTPIN (-4925 1925) $PN BL26
J 2
(-4935 1935);
DISPLAY 0.617021 (-4935 1935);
PAINT ORANGE (-4935 1935);
FORCEPROP 2 LASTPIN (-4925 1625) $PN BV16
J 2
(-4935 1635);
DISPLAY 0.617021 (-4935 1635);
PAINT ORANGE (-4935 1635);
FORCEPROP 2 LASTPIN (-4925 1725) $PN BN29
J 2
(-4935 1735);
DISPLAY 0.617021 (-4935 1735);
PAINT ORANGE (-4935 1735);
FORCEPROP 2 LASTPIN (-3125 1625) $PN BY16
J 0
(-3115 1635);
DISPLAY 0.617021 (-3115 1635);
PAINT ORANGE (-3115 1635);
FORCEPROP 2 LASTPIN (-4925 2675) $PN AT56
J 2
(-4935 2685);
DISPLAY 0.617021 (-4935 2685);
PAINT ORANGE (-4935 2685);
FORCEPROP 2 LASTPIN (-3125 3875) $PN BV19
J 0
(-3115 3885);
DISPLAY 0.617021 (-3115 3885);
PAINT ORANGE (-3115 3885);
FORCEPROP 2 LASTPIN (-3125 4175) $PN K9
J 0
(-3115 4185);
DISPLAY 0.617021 (-3115 4185);
PAINT ORANGE (-3115 4185);
FORCEPROP 2 LASTPIN (-3125 4375) $PN K13
J 0
(-3115 4385);
DISPLAY 0.617021 (-3115 4385);
PAINT ORANGE (-3115 4385);
FORCEPROP 2 LASTPIN (-3125 1925) $PN BL33
J 0
(-3115 1935);
DISPLAY 0.617021 (-3115 1935);
PAINT ORANGE (-3115 1935);
FORCEPROP 2 LASTPIN (-3125 1975) $PN BN33
J 0
(-3115 1985);
DISPLAY 0.617021 (-3115 1985);
PAINT ORANGE (-3115 1985);
FORCEPROP 2 LASTPIN (-3125 2075) $PN BM27
J 0
(-3115 2085);
DISPLAY 0.617021 (-3115 2085);
PAINT ORANGE (-3115 2085);
FORCEPROP 2 LASTPIN (-3125 2225) $PN BR24
J 0
(-3115 2235);
DISPLAY 0.617021 (-3115 2235);
PAINT ORANGE (-3115 2235);
FORCEPROP 2 LASTPIN (-3125 2175) $PN BM24
J 0
(-3115 2185);
DISPLAY 0.617021 (-3115 2185);
PAINT ORANGE (-3115 2185);
FORCEPROP 2 LASTPIN (-4925 2725) $PN AR54
J 2
(-4935 2735);
DISPLAY 0.617021 (-4935 2735);
PAINT ORANGE (-4935 2735);
FORCEPROP 2 LASTPIN (-4925 2825) $PN AD54
J 2
(-4935 2835);
DISPLAY 0.617021 (-4935 2835);
PAINT ORANGE (-4935 2835);
FORCEPROP 2 LASTPIN (-4925 2075) $PN BH31
J 2
(-4935 2085);
DISPLAY 0.617021 (-4935 2085);
PAINT ORANGE (-4935 2085);
FORCEPROP 2 LASTPIN (-4925 2425) $PN BF35
J 2
(-4935 2435);
DISPLAY 0.617021 (-4935 2435);
PAINT ORANGE (-4935 2435);
FORCEPROP 2 LASTPIN (-4925 2325) $PN BJ37
J 2
(-4935 2335);
DISPLAY 0.617021 (-4935 2335);
PAINT ORANGE (-4935 2335);
FORCEPROP 2 LASTPIN (-4925 2375) $PN BG37
J 2
(-4935 2385);
DISPLAY 0.617021 (-4935 2385);
PAINT ORANGE (-4935 2385);
FORCEPROP 2 LASTPIN (-4925 1975) $PN BN26
J 2
(-4935 1985);
DISPLAY 0.617021 (-4935 1985);
PAINT ORANGE (-4935 1985);
FORCEPROP 2 LASTPIN (-4925 3425) $PN AK54
J 2
(-4935 3435);
DISPLAY 0.617021 (-4935 3435);
PAINT ORANGE (-4935 3435);
FORCEPROP 2 LASTPIN (-4925 3475) $PN W54
J 2
(-4935 3485);
DISPLAY 0.617021 (-4935 3485);
PAINT ORANGE (-4935 3485);
FORCEPROP 2 LASTPIN (-4925 3325) $PN M7
J 2
(-4935 3335);
DISPLAY 0.617021 (-4935 3335);
PAINT ORANGE (-4935 3335);
FORCEPROP 2 LASTPIN (-4925 3075) $PN AP56
J 2
(-4935 3085);
DISPLAY 0.617021 (-4935 3085);
PAINT ORANGE (-4935 3085);
FORCEPROP 2 LASTPIN (-4925 3025) $PN AH54
J 2
(-4935 3035);
DISPLAY 0.617021 (-4935 3035);
PAINT ORANGE (-4935 3035);
FORCEPROP 2 LASTPIN (-4925 2975) $PN AF54
J 2
(-4935 2985);
DISPLAY 0.617021 (-4935 2985);
PAINT ORANGE (-4935 2985);
FORCEPROP 2 LASTPIN (-4925 2875) $PN U54
J 2
(-4935 2885);
DISPLAY 0.617021 (-4935 2885);
PAINT ORANGE (-4935 2885);
FORCEPROP 2 LASTPIN (-4925 2225) $PN BJ29
J 2
(-4935 2235);
DISPLAY 0.617021 (-4935 2235);
PAINT ORANGE (-4935 2235);
FORCEPROP 2 LASTPIN (-3125 2425) $PN BR31
J 0
(-3115 2435);
DISPLAY 0.617021 (-3115 2435);
PAINT ORANGE (-3115 2435);
FORCEPROP 2 LASTPIN (-4925 3125) $PN AN54
J 2
(-4935 3135);
DISPLAY 0.617021 (-4935 3135);
PAINT ORANGE (-4935 3135);
FORCEPROP 2 LASTPIN (-4925 3625) $PN AA54
J 2
(-4935 3635);
DISPLAY 0.617021 (-4935 3635);
PAINT ORANGE (-4935 3635);
FORCEPROP 2 LASTPIN (-4925 3775) $PN P22
J 2
(-4935 3785);
DISPLAY 0.617021 (-4935 3785);
PAINT ORANGE (-4935 3785);
FORCEPROP 2 LASTPIN (-4925 4075) $PN D14
J 2
(-4935 4085);
DISPLAY 0.617021 (-4935 4085);
PAINT ORANGE (-4935 4085);
FORCEPROP 1 LAST LOCATION U7C1
J 0
(-4900 4700);
DISPLAY 0.617021 (-4900 4700);
PAINT AQUA (-4900 4700);
FORCEPROP 2 LASTPIN (-4925 4425) $PN A13
J 2
(-4935 4435);
DISPLAY 0.617021 (-4935 4435);
PAINT ORANGE (-4935 4435);
FORCEPROP 2 LASTPIN (-4925 4175) $PN G11
J 2
(-4935 4185);
DISPLAY 0.617021 (-4935 4185);
PAINT ORANGE (-4935 4185);
FORCEPROP 2 LASTPIN (-4925 3875) $PN G15
J 2
(-4935 3885);
DISPLAY 0.617021 (-4935 3885);
PAINT ORANGE (-4935 3885);
FORCEPROP 2 LASTPIN (-3125 2825) $PN V15
J 0
(-3115 2835);
DISPLAY 0.617021 (-3115 2835);
PAINT ORANGE (-3115 2835);
FORCEPROP 2 LASTPIN (-3125 2475) $PN BM31
J 0
(-3115 2485);
DISPLAY 0.617021 (-3115 2485);
PAINT ORANGE (-3115 2485);
FORCEPROP 2 LASTPIN (-3125 2625) $PN V7
J 0
(-3115 2635);
DISPLAY 0.617021 (-3115 2635);
PAINT ORANGE (-3115 2635);
FORCEPROP 2 LASTPIN (-3125 2675) $PN U13
J 0
(-3115 2685);
DISPLAY 0.617021 (-3115 2685);
PAINT ORANGE (-3115 2685);
FORCEPROP 1 LAST PATH I73
J 0
(-4025 4625);
PAINT GREEN (-4025 4625);
DISPLAY INVISIBLE (-4025 4625);
FORCEPROP 2 LAST CDS_LIB mstr_u_proc
J 0
(-4025 3025);
PAINT ORANGE (-4025 3025);
DISPLAY INVISIBLE (-4025 3025);
FORCEPROP 0 LAST BOM_COST SB
J 0
(-4475 5025);
DISPLAY 1.361702 (-4475 5025);
PAINT ORANGE (-4475 5025);
DISPLAY INVISIBLE (-4475 5025);
FORCEPROP 0 LAST ROOM SB
J 0
(-4475 4925);
DISPLAY 1.361702 (-4475 4925);
PAINT ORANGE (-4475 4925);
DISPLAY INVISIBLE (-4475 4925);
FORCEPROP 1 LAST PACK_TYPE BGA1
J 0
(-4875 4725);
PAINT SKYBLUE (-4875 4725);
DISPLAY INVISIBLE (-4875 4725);
FORCEPROP 2 LAST SEC_TYPE BGA1
J 0
(-4900 4750);
DISPLAY 1.021277 (-4900 4750);
PAINT ORANGE (-4900 4750);
DISPLAY INVISIBLE (-4900 4750);
FORCEPROP 2 LAST SEC 5
J 0
(-4900 4750);
DISPLAY 0.680851 (-4900 4750);
PAINT MONO (-4900 4750);
DISPLAY INVISIBLE (-4900 4750);
FORCEPROP 2 LAST CDS_LOCATION U7C1
J 0
(-4900 4700);
DISPLAY 0.617021 (-4900 4700);
PAINT AQUA (-4900 4700);
DISPLAY INVISIBLE (-4900 4700);
FORCEADD CRYSTAL..1
(-7400 850);
FORCEPROP 1 LASTPIN (-7500 850) $PN 1
J 2
(-7455 860);
DISPLAY 0.617021 (-7455 860);
PAINT AQUA (-7455 860);
FORCEPROP 1 LAST MATERIAL IC
J 0
(-7411 766);
DISPLAY 0.617021 (-7411 766);
PAINT SKYBLUE (-7411 766);
FORCEPROP 1 LASTPIN (-7300 850) $PN 3
J 0
(-7335 860);
DISPLAY 0.617021 (-7335 860);
PAINT AQUA (-7335 860);
FORCEPROP 1 LAST VALUE 25.000MHZ
J 1
(-7393 911);
DISPLAY 0.617021 (-7393 911);
PAINT SKYBLUE (-7393 911);
FORCEPROP 1 LAST LOCATION Y8C1
J 1
(-7395 949);
DISPLAY 0.617021 (-7395 949);
PAINT AQUA (-7395 949);
FORCEPROP 1 LAST PART_NUMBER H19611-001
J 0
(-7575 1000);
DISPLAY 0.617021 (-7575 1000);
PAINT BLUE (-7575 1000);
FORCEPROP 0 LAST BOM_COST SB
J 0
(-7575 1125);
DISPLAY 1.021277 (-7575 1125);
PAINT ORANGE (-7575 1125);
DISPLAY INVISIBLE (-7575 1125);
FORCEPROP 2 LAST SEC 1
J 0
(-7575 1050);
DISPLAY 0.680851 (-7575 1050);
PAINT MONO (-7575 1050);
DISPLAY INVISIBLE (-7575 1050);
FORCEPROP 2 LAST SEC_TYPE 2013
J 0
(-7575 1050);
DISPLAY 1.021277 (-7575 1050);
PAINT ORANGE (-7575 1050);
DISPLAY INVISIBLE (-7575 1050);
FORCEPROP 0 LAST ROOM SB
J 0
(-7575 1075);
DISPLAY 1.021277 (-7575 1075);
PAINT ORANGE (-7575 1075);
DISPLAY INVISIBLE (-7575 1075);
FORCEPROP 1 LAST PATH I76
J 0
(-7375 950);
DISPLAY 0.872340 (-7375 950);
PAINT PINK (-7375 950);
DISPLAY INVISIBLE (-7375 950);
FORCEPROP 2 LAST CDS_LIB mstr_discrete
J 0
(-7400 850);
PAINT ORANGE (-7400 850);
DISPLAY INVISIBLE (-7400 850);
FORCEPROP 2 LAST CDS_LOCATION Y8C1
J 1
(-7395 949);
DISPLAY 0.617021 (-7395 949);
PAINT AQUA (-7395 949);
DISPLAY INVISIBLE (-7395 949);
FORCEPROP 1 LAST PACK_TYPE 2013
J 0
(-7412 758);
DISPLAY 0.702128 (-7412 758);
PAINT SKYBLUE (-7412 758);
DISPLAY INVISIBLE (-7412 758);
FORCEADD GND..1
(-7250 400);
FORCEPROP 3 LASTPIN (-7250 450) SIG_NAME GND\g
J 0
(-7240 460);
DISPLAY 0.659574 (-7240 460);
PAINT MONO (-7240 460);
DISPLAY INVISIBLE (-7240 460);
FORCEPROP 2 LAST CDS_LIB mstr_symbols
J 0
(-7250 400);
PAINT ORANGE (-7250 400);
DISPLAY INVISIBLE (-7250 400);
FORCEPROP 1 LAST PATH I78
J 0
(-7175 400);
DISPLAY 0.872340 (-7175 400);
PAINT AQUA (-7175 400);
DISPLAY INVISIBLE (-7175 400);
FORCEPROP 1 LAST SIZE 1B
J 0
(-7175 350);
DISPLAY 0.872340 (-7175 350);
PAINT AQUA (-7175 350);
DISPLAY INVISIBLE (-7175 350);
FORCEPROP 1 LAST VOLTAGE 0.0V
J 0
(-7295 357);
DISPLAY 0.340426 (-7295 357);
PAINT SKYBLUE (-7295 357);
DISPLAY INVISIBLE (-7295 357);
FORCEPROP 1 LAST BODY_TYPE PLUMBING
J 0
(-7295 357);
DISPLAY 0.340426 (-7295 357);
PAINT GREEN (-7295 357);
DISPLAY INVISIBLE (-7295 357);
FORCEPROP 1 LAST HDL_POWER GND
J 0
(-7250 550);
DISPLAY 0.872340 (-7250 550);
PAINT GREEN (-7250 550);
DISPLAY INVISIBLE (-7250 550);
FORCEADD GND..1
(-7700 400);
FORCEPROP 3 LASTPIN (-7700 450) SIG_NAME GND\g
J 0
(-7690 460);
DISPLAY 0.659574 (-7690 460);
PAINT MONO (-7690 460);
DISPLAY INVISIBLE (-7690 460);
FORCEPROP 1 LAST PATH I80
J 0
(-7625 400);
DISPLAY 0.872340 (-7625 400);
PAINT AQUA (-7625 400);
DISPLAY INVISIBLE (-7625 400);
FORCEPROP 1 LAST SIZE 1B
J 0
(-7625 350);
DISPLAY 0.872340 (-7625 350);
PAINT AQUA (-7625 350);
DISPLAY INVISIBLE (-7625 350);
FORCEPROP 2 LAST CDS_LIB mstr_symbols
J 0
(-7700 400);
PAINT ORANGE (-7700 400);
DISPLAY INVISIBLE (-7700 400);
FORCEPROP 1 LAST VOLTAGE 0.0V
J 0
(-7745 357);
DISPLAY 0.340426 (-7745 357);
PAINT SKYBLUE (-7745 357);
DISPLAY INVISIBLE (-7745 357);
FORCEPROP 1 LAST BODY_TYPE PLUMBING
J 0
(-7745 357);
DISPLAY 0.340426 (-7745 357);
PAINT GREEN (-7745 357);
DISPLAY INVISIBLE (-7745 357);
FORCEPROP 1 LAST HDL_POWER GND
J 0
(-7700 550);
DISPLAY 0.872340 (-7700 550);
PAINT GREEN (-7700 550);
DISPLAY INVISIBLE (-7700 550);
FORCEADD OFFPAGE..2
(-7125 1150);
FORCEPROP 2 LAST $XR0 118 
J 0
(-6936 1150);
DISPLAY 0.638298 (-6936 1150);
PAINT MONO (-6936 1150);
FORCEPROP 2 LAST PATH I86
J 0
(-6950 1225);
DISPLAY 1.021277 (-6950 1225);
PAINT ORANGE (-6950 1225);
DISPLAY INVISIBLE (-6950 1225);
FORCEPROP 2 LAST CDS_LIB mstr_standard
J 0
(-7125 1150);
PAINT ORANGE (-7125 1150);
DISPLAY INVISIBLE (-7125 1150);
FORCEPROP 1 LAST OFFPAGE TRUE
J 0
(-6800 1025);
DISPLAY 0.872340 (-6800 1025);
PAINT GREEN (-6800 1025);
DISPLAY INVISIBLE (-6800 1025);
FORCEPROP 1 LAST COMMENT_BODY TRUE
J 0
(-7170 1055);
DISPLAY 0.872340 (-7170 1055);
PAINT GREEN (-7170 1055);
DISPLAY INVISIBLE (-7170 1055);
FORCEADD OFFPAGE..2
(-6750 850);
FORCEPROP 2 LAST $XR0 118 
J 0
(-6561 850);
DISPLAY 0.638298 (-6561 850);
PAINT MONO (-6561 850);
FORCEPROP 2 LAST PATH I87
J 0
(-6575 925);
DISPLAY 1.021277 (-6575 925);
PAINT ORANGE (-6575 925);
DISPLAY INVISIBLE (-6575 925);
FORCEPROP 2 LAST CDS_LIB mstr_standard
J 0
(-6750 850);
PAINT ORANGE (-6750 850);
DISPLAY INVISIBLE (-6750 850);
FORCEPROP 1 LAST OFFPAGE TRUE
J 0
(-6425 725);
DISPLAY 0.872340 (-6425 725);
PAINT GREEN (-6425 725);
DISPLAY INVISIBLE (-6425 725);
FORCEPROP 1 LAST COMMENT_BODY TRUE
J 0
(-6795 755);
DISPLAY 0.872340 (-6795 755);
PAINT GREEN (-6795 755);
DISPLAY INVISIBLE (-6795 755);
FORCEADD OFFPAGE..1
(-5675 1625);
FORCEPROP 2 LAST $XR0 118 
J 0
(-5957 1625);
DISPLAY 0.638298 (-5957 1625);
PAINT MONO (-5957 1625);
FORCEPROP 2 LAST PATH I89
J 0
(-5625 1700);
DISPLAY 1.021277 (-5625 1700);
PAINT ORANGE (-5625 1700);
DISPLAY INVISIBLE (-5625 1700);
FORCEPROP 2 LAST CDS_LIB mstr_standard
J 0
(-5675 1625);
PAINT ORANGE (-5675 1625);
DISPLAY INVISIBLE (-5675 1625);
FORCEPROP 1 LAST OFFPAGE TRUE
J 0
(-5350 1500);
DISPLAY 0.872340 (-5350 1500);
PAINT GREEN (-5350 1500);
DISPLAY INVISIBLE (-5350 1500);
FORCEPROP 1 LAST COMMENT_BODY TRUE
J 0
(-5550 1525);
DISPLAY 0.872340 (-5550 1525);
PAINT GREEN (-5550 1525);
DISPLAY INVISIBLE (-5550 1525);
FORCEADD OFFPAGE..2
(-1950 1625);
FORCEPROP 2 LAST $XR0 118 
J 0
(-1761 1625);
DISPLAY 0.638298 (-1761 1625);
PAINT MONO (-1761 1625);
FORCEPROP 2 LAST PATH I91
J 0
(-1775 1700);
DISPLAY 1.021277 (-1775 1700);
PAINT ORANGE (-1775 1700);
DISPLAY INVISIBLE (-1775 1700);
FORCEPROP 2 LAST CDS_LIB mstr_standard
J 0
(-1950 1625);
PAINT ORANGE (-1950 1625);
DISPLAY INVISIBLE (-1950 1625);
FORCEPROP 1 LAST OFFPAGE TRUE
J 0
(-1625 1500);
DISPLAY 0.872340 (-1625 1500);
PAINT GREEN (-1625 1500);
DISPLAY INVISIBLE (-1625 1500);
FORCEPROP 1 LAST COMMENT_BODY TRUE
J 0
(-1995 1530);
DISPLAY 0.872340 (-1995 1530);
PAINT GREEN (-1995 1530);
DISPLAY INVISIBLE (-1995 1530);
FORCEADD RES..2
(-7225 2175);
FORCEPROP 1 LAST MATERIAL CHIP
J 0
(-7185 2100);
DISPLAY 0.617021 (-7185 2100);
PAINT SKYBLUE (-7185 2100);
FORCEPROP 1 LASTPIN (-7225 2275) $PN 1
J 0
(-7220 2237);
DISPLAY 0.617021 (-7220 2237);
PAINT ORANGE (-7220 2237);
FORCEPROP 1 LASTPIN (-7225 2075) $PN 2
J 0
(-7220 2085);
DISPLAY 0.617021 (-7220 2085);
PAINT ORANGE (-7220 2085);
FORCEPROP 1 LAST PACK_TYPE 0402
J 0
(-7185 2000);
DISPLAY 0.617021 (-7185 2000);
PAINT SKYBLUE (-7185 2000);
FORCEPROP 1 LAST PART_NUMBER G85996-004
J 0
(-7185 2050);
DISPLAY 0.617021 (-7185 2050);
PAINT BLUE (-7185 2050);
FORCEPROP 1 LAST WATTAGE 1/16W
J 0
(-7185 2150);
DISPLAY 0.617021 (-7185 2150);
PAINT SKYBLUE (-7185 2150);
FORCEPROP 1 LAST TOLERANCE 0.1%
J 0
(-7180 2200);
DISPLAY 0.617021 (-7180 2200);
PAINT SKYBLUE (-7180 2200);
FORCEPROP 1 LAST VALUE 1.0K
J 0
(-7180 2250);
DISPLAY 0.617021 (-7180 2250);
PAINT SKYBLUE (-7180 2250);
FORCEPROP 1 LAST LOCATION R2N4
J 0
(-7180 2300);
DISPLAY 0.617021 (-7180 2300);
PAINT AQUA (-7180 2300);
FORCEPROP 2 LAST SEC 1
J 0
(-7175 2400);
DISPLAY 0.680851 (-7175 2400);
PAINT MONO (-7175 2400);
DISPLAY INVISIBLE (-7175 2400);
FORCEPROP 2 LAST SEC_TYPE 0402
J 0
(-7175 2400);
DISPLAY 1.021277 (-7175 2400);
PAINT ORANGE (-7175 2400);
DISPLAY INVISIBLE (-7175 2400);
FORCEPROP 1 LAST PATH I96
J 0
(-7175 2350);
DISPLAY 0.978723 (-7175 2350);
PAINT WHITE (-7175 2350);
DISPLAY INVISIBLE (-7175 2350);
FORCEPROP 0 LAST ROOM SB
J 0
(-7175 2400);
DISPLAY 1.021277 (-7175 2400);
PAINT ORANGE (-7175 2400);
DISPLAY INVISIBLE (-7175 2400);
FORCEPROP 2 LAST CDS_LOCATION R2N4
J 0
(-7180 2300);
DISPLAY 0.617021 (-7180 2300);
PAINT AQUA (-7180 2300);
DISPLAY INVISIBLE (-7180 2300);
FORCEPROP 2 LAST CDS_LIB mstr_discrete
J 0
(-7225 2175);
PAINT ORANGE (-7225 2175);
DISPLAY INVISIBLE (-7225 2175);
FORCEADD RES..1
(-1700 1875);
FORCEPROP 1 LAST MATERIAL CHIP
J 0
(-1700 1725);
DISPLAY 0.617021 (-1700 1725);
PAINT SKYBLUE (-1700 1725);
FORCEPROP 1 LASTPIN (-1600 1875) $PN 2
J 0
(-1638 1887);
DISPLAY 0.617021 (-1638 1887);
PAINT ORANGE (-1638 1887);
FORCEPROP 1 LAST TOLERANCE 0.1%
J 0
(-1700 1775);
DISPLAY 0.617021 (-1700 1775);
PAINT SKYBLUE (-1700 1775);
FORCEPROP 1 LAST PACK_TYPE 0402
J 0
(-1600 1775);
DISPLAY 0.617021 (-1600 1775);
PAINT SKYBLUE (-1600 1775);
FORCEPROP 1 LASTPIN (-1800 1875) $PN 1
J 0
(-1788 1887);
DISPLAY 0.617021 (-1788 1887);
PAINT ORANGE (-1788 1887);
FORCEPROP 1 LAST PART_NUMBER G85996-004
J 0
(-1750 1975);
DISPLAY 0.617021 (-1750 1975);
PAINT BLUE (-1750 1975);
FORCEPROP 1 LAST LOCATION R2M6
J 0
(-1750 1925);
DISPLAY 0.617021 (-1750 1925);
PAINT AQUA (-1750 1925);
FORCEPROP 1 LAST VALUE 1.0K
J 2
(-1725 1775);
DISPLAY 0.617021 (-1725 1775);
PAINT SKYBLUE (-1725 1775);
FORCEPROP 1 LAST WATTAGE 1/16W
J 2
(-1725 1725);
DISPLAY 0.617021 (-1725 1725);
PAINT SKYBLUE (-1725 1725);
FORCEPROP 2 LAST SEC 1
J 0
(-1750 2075);
DISPLAY 0.680851 (-1750 2075);
PAINT MONO (-1750 2075);
DISPLAY INVISIBLE (-1750 2075);
FORCEPROP 2 LAST SEC_TYPE 0402
J 0
(-1750 2075);
DISPLAY 1.021277 (-1750 2075);
PAINT ORANGE (-1750 2075);
DISPLAY INVISIBLE (-1750 2075);
FORCEPROP 0 LAST ROOM SB
J 0
(-1650 2100);
DISPLAY 1.021277 (-1650 2100);
PAINT ORANGE (-1650 2100);
DISPLAY INVISIBLE (-1650 2100);
FORCEPROP 1 LAST PATH I99
J 0
(-1750 2025);
DISPLAY 0.978723 (-1750 2025);
PAINT WHITE (-1750 2025);
DISPLAY INVISIBLE (-1750 2025);
FORCEPROP 2 LAST CDS_LIB mstr_discrete
J 0
(-1700 1875);
PAINT ORANGE (-1700 1875);
DISPLAY INVISIBLE (-1700 1875);
FORCEPROP 2 LAST CDS_LOCATION R2M6
J 0
(-1750 1925);
DISPLAY 0.617021 (-1750 1925);
PAINT AQUA (-1750 1925);
DISPLAY INVISIBLE (-1750 1925);
FORCEADD DNS..2
(-1070 2470);
PAINT RED (-1070 2470);
FORCEPROP 2 LAST CDS_LIB mstr_misc
J 0
(-1070 2470);
PAINT ORANGE (-1070 2470);
DISPLAY INVISIBLE (-1070 2470);
FORCEPROP 1 LAST COMMENT_BODY TRUE
R 1
J 0
(-995 2245);
DISPLAY 0.872340 (-995 2245);
PAINT GREEN (-995 2245);
DISPLAY INVISIBLE (-995 2245);
FORCEADD CAD_NOTE..1
(-1275 1775);
FORCEPROP 0 LAST L1 MUST PLACE LAN_BIAS RES
J 0
(-1425 1650);
DISPLAY 0.936170 (-1425 1650);
PAINT WHITE (-1425 1650);
FORCEPROP 0 LAST L2 WITHIN 3 INCHES OF PCH
J 0
(-1425 1575);
DISPLAY 0.936170 (-1425 1575);
PAINT WHITE (-1425 1575);
FORCEPROP 2 LAST CDS_LIB mstr_symbols
J 0
(-1275 1775);
PAINT ORANGE (-1275 1775);
DISPLAY INVISIBLE (-1275 1775);
FORCEPROP 2 LAST ROOM P1V8_PCH_STBY_VR
J 0
(-1425 1725);
DISPLAY 1.659574 (-1425 1725);
PAINT ORANGE (-1425 1725);
DISPLAY INVISIBLE (-1425 1725);
FORCEPROP 1 LAST COMMENT_BODY TRUE
J 0
(-1250 1875);
DISPLAY 2.212766 (-1250 1875);
PAINT PEACH (-1250 1875);
DISPLAY INVISIBLE (-1250 1875);
FORCEADD CAD_NOTE..1
(-7575 1800);
FORCEPROP 0 LAST L1 MUST PLACE LAN_RBIAS RES
J 0
(-7725 1675);
DISPLAY 0.936170 (-7725 1675);
PAINT WHITE (-7725 1675);
FORCEPROP 0 LAST L2 WITHIN 3 INCHES OF PCH
J 0
(-7725 1600);
DISPLAY 0.936170 (-7725 1600);
PAINT WHITE (-7725 1600);
FORCEPROP 2 LAST CDS_LIB mstr_symbols
J 0
(-7575 1800);
PAINT ORANGE (-7575 1800);
DISPLAY INVISIBLE (-7575 1800);
FORCEPROP 2 LAST ROOM P1V8_PCH_STBY_VR
J 0
(-7725 1750);
DISPLAY 1.659574 (-7725 1750);
PAINT ORANGE (-7725 1750);
DISPLAY INVISIBLE (-7725 1750);
FORCEPROP 1 LAST COMMENT_BODY TRUE
J 0
(-7550 1900);
DISPLAY 2.212766 (-7550 1900);
PAINT PEACH (-7550 1900);
DISPLAY INVISIBLE (-7550 1900);
FORCEADD DNS..2
(-1670 670);
PAINT RED (-1670 670);
FORCEPROP 2 LAST CDS_LIB mstr_misc
J 0
(-1670 670);
PAINT ORANGE (-1670 670);
DISPLAY INVISIBLE (-1670 670);
FORCEPROP 1 LAST COMMENT_BODY TRUE
R 1
J 0
(-1595 445);
DISPLAY 0.872340 (-1595 445);
PAINT GREEN (-1595 445);
DISPLAY INVISIBLE (-1595 445);
FORCEADD CAD_NOTE..1
(-4775 625);
FORCEPROP 0 LAST L1 PLACE CAP CLOSE TO VCC PIN
J 0
(-4925 500);
DISPLAY 1.021277 (-4925 500);
PAINT ORANGE (-4925 500);
FORCEPROP 2 LAST CDS_LIB mstr_symbols
J 0
(-4775 625);
PAINT ORANGE (-4775 625);
DISPLAY INVISIBLE (-4775 625);
FORCEPROP 1 LAST COMMENT_BODY TRUE
J 0
(-4750 725);
DISPLAY 0.978723 (-4750 725);
PAINT ORANGE (-4750 725);
DISPLAY INVISIBLE (-4750 725);
FORCEADD CAD_NOTE..1
(-7175 3725);
FORCEPROP 0 LAST L1 PLACE RST_BMC_SRST# RES CLOSE TO PCH
J 0
(-7325 3600);
DISPLAY 0.936170 (-7325 3600);
PAINT WHITE (-7325 3600);
FORCEPROP 2 LAST CDS_LIB mstr_symbols
J 0
(-7175 3725);
PAINT ORANGE (-7175 3725);
DISPLAY INVISIBLE (-7175 3725);
FORCEPROP 2 LAST ROOM P1V8_PCH_STBY_VR
J 0
(-7325 3675);
DISPLAY 1.659574 (-7325 3675);
PAINT ORANGE (-7325 3675);
DISPLAY INVISIBLE (-7325 3675);
FORCEPROP 1 LAST COMMENT_BODY TRUE
J 0
(-7150 3825);
DISPLAY 2.212766 (-7150 3825);
PAINT PEACH (-7150 3825);
DISPLAY INVISIBLE (-7150 3825);
FORCEADD INTEL_CORP_BPAGE..1
(0 0);
FORCEPROP 1 LAST CDS_CON_LAST_MODIFIED Fri Jun 16 17:48:46 2017
J 0
(-1425 325);
DISPLAY 1.340426 (-1425 325);
PAINT ORANGE (-1425 325);
DISPLAY INVISIBLE (-1425 325);
FORCEPROP 1 LAST CUSTOM_TXT_CDS <CURRENT_DESIGN_SHEET> OF <TOTAL_DESIGN_SHEETS>
J 0
(-500 25);
PAINT ORANGE (-500 25);
FORCEPROP 1 LAST CUSTOM_TXT_CDS <CON_LAST_MODIFIED>
J 0
(-4000 100);
PAINT ORANGE (-4000 100);
FORCEPROP 2 LAST CUSTOM_TXT_CDS <XR_PAGE_TITLE>
J 0
(-7890 5250);
DISPLAY 0.638298 (-7890 5250);
PAINT PINK (-7890 5250);
DISPLAY INVISIBLE (-7890 5250);
FORCEPROP 1 LAST SCH_TITLE LEWISBURG 5/11 LAN
J 0
(-7950 50);
DISPLAY 1.212766 (-7950 50);
PAINT YELLOW (-7950 50);
FORCEPROP 2 LAST CDS_LIB mstr_symbols
J 0
(0 0);
PAINT ORANGE (0 0);
DISPLAY INVISIBLE (0 0);
FORCEPROP 2 LAST PAGE_BORDER TRUE
J 0
(-7890 5250);
DISPLAY 0.851064 (-7890 5250);
PAINT PINK (-7890 5250);
DISPLAY INVISIBLE (-7890 5250);
FORCEPROP 1 LAST COMMENT_BODY TRUE
J 0
(12 12);
DISPLAY 0.638298 (12 12);
PAINT PEACH (12 12);
DISPLAY INVISIBLE (12 12);
FORCEPROP 2 LAST CDS_XR_PAGE_TITLE CR-118 : @BASEBOARD_FAB2_LIB.BASEBOARD_FAB2(SCH_1):PAGE118
J 0
(-7890 5250);
DISPLAY 0.638298 (-7890 5250);
PAINT PINK (-7890 5250);
DISPLAY INVISIBLE (-7890 5250);
FORCEADD DNS..2
(-2720 3645);
PAINT RED (-2720 3645);
FORCEPROP 2 LAST CDS_LIB mstr_misc
J 0
(-2720 3645);
PAINT ORANGE (-2720 3645);
DISPLAY INVISIBLE (-2720 3645);
FORCEPROP 1 LAST COMMENT_BODY TRUE
R 1
J 0
(-2645 3420);
DISPLAY 0.872340 (-2645 3420);
PAINT GREEN (-2645 3420);
DISPLAY INVISIBLE (-2645 3420);
FORCEADD CAD_NOTE..1
(-6700 550);
FORCEPROP 0 LAST L1 PLACE ON TOP LAYER ONLY
J 0
(-6850 425);
DISPLAY 0.936170 (-6850 425);
PAINT WHITE (-6850 425);
FORCEPROP 2 LAST CDS_LIB mstr_symbols
J 0
(-6700 550);
PAINT MONO (-6700 550);
DISPLAY INVISIBLE (-6700 550);
FORCEPROP 1 LAST COMMENT_BODY TRUE
J 0
(-6675 650);
DISPLAY 1.595745 (-6675 650);
PAINT PEACH (-6675 650);
DISPLAY INVISIBLE (-6675 650);
WIRE 16 -1 (-1000 1975)(-1000 1875);
WIRE 16 -1 (-1000 1875)(-1600 1875);
WIRE 16 -1 (-7225 2275)(-7225 2350);
WIRE 16 -1 (-2200 1200)(-2200 1225);
WIRE 16 -1 (-5200 475)(-5200 575);
WIRE 16 -1 (-5200 175)(-5200 275);
WIRE 16 -1 (-5175 1375)(-5175 1400);
WIRE 16 -1 (-6450 4800)(-6450 4850);
WIRE 16 -1 (-6450 4800)(-6200 4800);
WIRE 16 -1 (-6450 4700)(-6450 4800);
WIRE 16 -1 (-6200 4800)(-6200 4700);
WIRE 16 -1 (-1075 2375)(-1075 2275);
WIRE 16 -1 (-2300 4750)(-2300 4825);
WIRE 16 -1 (-7250 450)(-7250 500);
WIRE 16 -1 (-7700 450)(-7700 500);
WIRE 16 -1 (-5725 3925)(-4925 3925);
FORCEPROP 2 LAST SIG_NAME FM_CPU1_SKTOCC_LVT3_N
J 0
(-5725 3935);
DISPLAY 0.617021 (-5725 3935);
PAINT ORANGE (-5725 3935);
WIRE 16 -1 (-6525 3975)(-6200 3975);
WIRE 16 -1 (-6200 3975)(-4925 3975);
FORCEPROP 2 LAST SIG_NAME RST_BMC_SRST_R_N
J 0
(-5725 3985);
DISPLAY 0.617021 (-5725 3985);
PAINT ORANGE (-5725 3985);
FORCEPROP 2 LASTPROP $XRERR UNIQUE?
J 0
(-5965 3985);
DISPLAY 0.638298 (-5965 3985);
PAINT MONO (-5965 3985);
DISPLAY INVISIBLE (-5965 3985);
WIRE 16 -1 (-6200 4500)(-6200 3975);
WIRE 16 -1 (-4925 4375)(-6550 4375);
FORCEPROP 0 LAST SIG_NAME FM_CPU0_RC_ERROR_R_N
J 0
(-5725 4386);
DISPLAY 0.617021 (-5725 4386);
PAINT ORANGE (-5725 4386);
FORCEPROP 2 LASTPROP $XRERR UNIQUE?
J 0
(-5965 4386);
DISPLAY 0.638298 (-5965 4386);
PAINT MONO (-5965 4386);
DISPLAY INVISIBLE (-5965 4386);
WIRE 16 -1 (-6550 4225)(-6450 4225);
WIRE 16 -1 (-6450 4500)(-6450 4225);
WIRE 16 -1 (-4925 4225)(-6450 4225);
FORCEPROP 2 LAST SIG_NAME FM_BATTERY_SENSE_EN_R_N
J 0
(-5700 4235);
DISPLAY 0.617021 (-5700 4235);
PAINT ORANGE (-5700 4235);
FORCEPROP 2 LASTPROP $XRERR UNIQUE?
J 0
(-5940 4235);
DISPLAY 0.638298 (-5940 4235);
PAINT MONO (-5940 4235);
DISPLAY INVISIBLE (-5940 4235);
WIRE 16 -1 (-1975 2775)(-3125 2775);
FORCEPROP 2 LAST SIG_NAME PECI_PCH
J 0
(-2535 2775);
DISPLAY 0.617021 (-2535 2775);
PAINT ORANGE (-2535 2775);
WIRE 16 -1 (-3125 2675)(-1675 2675);
FORCEPROP 2 LAST SIG_NAME H_PM_SYNC1_GTL_R
J 0
(-2535 2675);
DISPLAY 0.617021 (-2535 2675);
PAINT ORANGE (-2535 2675);
FORCEPROP 2 LASTPROP $XRERR UNIQUE?
J 0
(-2775 2675);
DISPLAY 0.638298 (-2775 2675);
PAINT MONO (-2775 2675);
DISPLAY INVISIBLE (-2775 2675);
WIRE 16 -1 (-1975 2825)(-3125 2825);
FORCEPROP 2 LAST SIG_NAME FM_PCH_LVC1_THERMTRIP_N
J 0
(-2535 2825);
DISPLAY 0.617021 (-2535 2825);
PAINT ORANGE (-2535 2825);
WIRE 16 -1 (-2575 2625)(-3125 2625);
FORCEPROP 2 LAST SIG_NAME TP_PM_SYNC_GTL
J 0
(-2975 2635);
DISPLAY 0.617021 (-2975 2635);
PAINT ORANGE (-2975 2635);
FORCEPROP 2 LASTPROP $XRERR UNIQUE?
J 0
(-2545 2625);
DISPLAY 0.638298 (-2545 2625);
PAINT MONO (-2545 2625);
DISPLAY INVISIBLE (-2545 2625);
WIRE 16 -1 (-3125 2925)(-2575 2925);
FORCEPROP 2 LAST SIG_NAME TP_PCH_RSVD54
J 0
(-2975 2935);
DISPLAY 0.617021 (-2975 2935);
PAINT ORANGE (-2975 2935);
FORCEPROP 2 LASTPROP $XRERR UNIQUE?
J 0
(-2545 2925);
DISPLAY 0.638298 (-2545 2925);
PAINT MONO (-2545 2925);
DISPLAY INVISIBLE (-2545 2925);
WIRE 16 -1 (-3125 2975)(-2575 2975);
FORCEPROP 2 LAST SIG_NAME TP_PCH_RSVD53
J 0
(-2975 2985);
DISPLAY 0.617021 (-2975 2985);
PAINT ORANGE (-2975 2985);
FORCEPROP 2 LASTPROP $XRERR UNIQUE?
J 0
(-2545 2975);
DISPLAY 0.638298 (-2545 2975);
PAINT MONO (-2545 2975);
DISPLAY INVISIBLE (-2545 2975);
WIRE 16 -1 (-2575 2175)(-3125 2175);
FORCEPROP 0 LAST SIG_NAME KR_P1_OCP_TX_DN
J 0
(-2950 2185);
DISPLAY 0.617021 (-2950 2185);
PAINT ORANGE (-2950 2185);
WIRE 16 -1 (-3125 2075)(-3000 2075);
WIRE 16 -1 (-3000 2050)(-3000 2075);
WIRE 16 -1 (-3000 2050)(-2575 2050);
FORCEPROP 0 LAST SIG_NAME KR_P0_OCP_TX_DN
J 0
(-2950 2060);
DISPLAY 0.617021 (-2950 2060);
PAINT ORANGE (-2950 2060);
WIRE 16 -1 (-2000 1625)(-3125 1625);
FORCEPROP 2 LAST SIG_NAME XTAL_KR_25M_OUT
J 0
(-2535 1635);
DISPLAY 0.617021 (-2535 1635);
PAINT ORANGE (-2535 1635);
WIRE 16 -1 (-3125 1875)(-1800 1875);
FORCEPROP 0 LAST SIG_NAME A_KR1_RBIAS
J 0
(-2535 1885);
DISPLAY 0.617021 (-2535 1885);
PAINT ORANGE (-2535 1885);
FORCEPROP 2 LASTPROP $XRERR UNIQUE?
J 0
(-2775 1885);
DISPLAY 0.638298 (-2775 1885);
PAINT MONO (-2775 1885);
DISPLAY INVISIBLE (-2775 1885);
WIRE 16 -1 (-5725 4125)(-4925 4125);
FORCEPROP 2 LAST SIG_NAME FM_SLPS4_N
J 0
(-5725 4135);
DISPLAY 0.617021 (-5725 4135);
PAINT ORANGE (-5725 4135);
WIRE 16 -1 (-5725 4175)(-4925 4175);
FORCEPROP 2 LAST SIG_NAME FM_CPU0_SKTOCC_LVT3_N
J 0
(-5725 4185);
DISPLAY 0.617021 (-5725 4185);
PAINT ORANGE (-5725 4185);
WIRE 16 -1 (-6550 4075)(-4925 4075);
FORCEPROP 2 LAST SIG_NAME FM_SLPS3_R_N
J 0
(-5700 4085);
DISPLAY 0.617021 (-5700 4085);
PAINT ORANGE (-5700 4085);
FORCEPROP 2 LASTPROP $XRERR UNIQUE?
J 0
(-5940 4085);
DISPLAY 0.638298 (-5940 4085);
PAINT MONO (-5940 4085);
DISPLAY INVISIBLE (-5940 4085);
WIRE 16 -1 (-5725 3875)(-4925 3875);
FORCEPROP 2 LAST SIG_NAME XDP_PCH_PWR_DEBUG_N
J 0
(-5725 3885);
DISPLAY 0.617021 (-5725 3885);
PAINT ORANGE (-5725 3885);
WIRE 3 682 (-5200 4300)(-5200 4750);
WIRE 16 -1 (-5725 4425)(-4925 4425);
FORCEPROP 2 LAST SIG_NAME FM_GBE_LOM_DISABLE_N
J 0
(-5725 4435);
DISPLAY 0.617021 (-5725 4435);
PAINT ORANGE (-5725 4435);
WIRE 16 -1 (-5725 4025)(-4925 4025);
FORCEPROP 2 LAST SIG_NAME FM_PCH_PWRBTN_N
J 0
(-5725 4035);
DISPLAY 0.617021 (-5725 4035);
PAINT ORANGE (-5725 4035);
WIRE 16 -1 (-5575 3775)(-4925 3775);
FORCEPROP 2 LAST SIG_NAME TP_PCH_RSVD45
J 0
(-5550 3785);
DISPLAY 0.617021 (-5550 3785);
PAINT ORANGE (-5550 3785);
FORCEPROP 2 LASTPROP $XRERR UNIQUE?
J 0
(-5815 3775);
DISPLAY 0.638298 (-5815 3775);
PAINT MONO (-5815 3775);
DISPLAY INVISIBLE (-5815 3775);
WIRE 16 -1 (-5575 3625)(-4925 3625);
FORCEPROP 2 LAST SIG_NAME TP_PCH_RSVD32
J 0
(-5550 3635);
DISPLAY 0.617021 (-5550 3635);
PAINT ORANGE (-5550 3635);
FORCEPROP 2 LASTPROP $XRERR UNIQUE?
J 0
(-5815 3625);
DISPLAY 0.638298 (-5815 3625);
PAINT MONO (-5815 3625);
DISPLAY INVISIBLE (-5815 3625);
WIRE 16 -1 (-5575 3575)(-4925 3575);
FORCEPROP 2 LAST SIG_NAME TP_PCH_RSVD33
J 0
(-5550 3585);
DISPLAY 0.617021 (-5550 3585);
PAINT ORANGE (-5550 3585);
FORCEPROP 2 LASTPROP $XRERR UNIQUE?
J 0
(-5815 3575);
DISPLAY 0.638298 (-5815 3575);
PAINT MONO (-5815 3575);
DISPLAY INVISIBLE (-5815 3575);
WIRE 16 -1 (-5575 3525)(-4925 3525);
FORCEPROP 2 LAST SIG_NAME TP_PCH_RSVD34
J 0
(-5550 3535);
DISPLAY 0.617021 (-5550 3535);
PAINT ORANGE (-5550 3535);
FORCEPROP 2 LASTPROP $XRERR UNIQUE?
J 0
(-5815 3525);
DISPLAY 0.638298 (-5815 3525);
PAINT MONO (-5815 3525);
DISPLAY INVISIBLE (-5815 3525);
WIRE 16 -1 (-5575 3475)(-4925 3475);
FORCEPROP 2 LAST SIG_NAME TP_PCH_RSVD35
J 0
(-5550 3485);
DISPLAY 0.617021 (-5550 3485);
PAINT ORANGE (-5550 3485);
FORCEPROP 2 LASTPROP $XRERR UNIQUE?
J 0
(-5815 3475);
DISPLAY 0.638298 (-5815 3475);
PAINT MONO (-5815 3475);
DISPLAY INVISIBLE (-5815 3475);
WIRE 16 -1 (-5575 3425)(-4925 3425);
FORCEPROP 2 LAST SIG_NAME TP_PCH_RSVD36
J 0
(-5550 3435);
DISPLAY 0.617021 (-5550 3435);
PAINT ORANGE (-5550 3435);
FORCEPROP 2 LASTPROP $XRERR UNIQUE?
J 0
(-5815 3425);
DISPLAY 0.638298 (-5815 3425);
PAINT MONO (-5815 3425);
DISPLAY INVISIBLE (-5815 3425);
WIRE 3 2175 (-3025 2550)(-3025 2150);
WIRE 3 2175 (-3025 2150)(-2275 2150);
WIRE 3 2175 (-3025 2550)(-2275 2550);
WIRE 3 2175 (-2275 2550)(-2275 2150);
WIRE 3 682 (-2200 2150)(-2250 2150);
WIRE 3 682 (-2200 2250)(-2200 2150);
WIRE 3 682 (-2250 2250)(-2200 2250);
WIRE 16 -1 (-2625 3650)(-1975 3650);
FORCEPROP 2 LAST SIG_NAME RST_SYSTEM_BTN_BUF_N
J 0
(-2610 3660);
DISPLAY 0.638298 (-2610 3660);
PAINT ORANGE (-2610 3660);
WIRE 16 -1 (-1075 2675)(-1075 2575);
WIRE 16 -1 (-650 2675)(-1075 2675);
FORCEPROP 2 LAST SIG_NAME H_PM_SYNC_GTL
J 0
(-1060 2685);
DISPLAY 0.617021 (-1060 2685);
PAINT ORANGE (-1060 2685);
WIRE 16 -1 (-1475 2675)(-1075 2675);
WIRE 16 -1 (-5150 2125)(-4925 2125);
WIRE 16 -1 (-5600 2100)(-5150 2100);
FORCEPROP 0 LAST SIG_NAME KR_P0_OCP_RX_C_DP
J 0
(-5575 2110);
DISPLAY 0.617021 (-5575 2110);
PAINT ORANGE (-5575 2110);
WIRE 16 -1 (-5150 2100)(-5150 2125);
WIRE 16 -1 (-4925 2225)(-5600 2225);
FORCEPROP 0 LAST SIG_NAME KR_P1_OCP_RX_C_DP
J 0
(-5575 2235);
DISPLAY 0.617021 (-5575 2235);
PAINT ORANGE (-5575 2235);
WIRE 3 682 (-6025 2150)(-5975 2150);
WIRE 3 682 (-6025 2250)(-6025 2150);
WIRE 3 682 (-5975 2250)(-6025 2250);
WIRE 16 -1 (-5625 2725)(-4925 2725);
FORCEPROP 2 LAST SIG_NAME XDP_ITP_PMODE
J 0
(-5625 2735);
DISPLAY 0.617021 (-5625 2735);
PAINT ORANGE (-5625 2735);
WIRE 16 -1 (-5625 2825)(-4925 2825);
FORCEPROP 2 LAST SIG_NAME XDP_PRDY_N
J 0
(-5625 2835);
DISPLAY 0.617021 (-5625 2835);
PAINT ORANGE (-5625 2835);
WIRE 16 -1 (-2575 2225)(-3125 2225);
FORCEPROP 0 LAST SIG_NAME KR_P1_OCP_TX_DP
J 0
(-2950 2235);
DISPLAY 0.617021 (-2950 2235);
PAINT ORANGE (-2950 2235);
WIRE 16 -1 (-3000 2100)(-2575 2100);
FORCEPROP 0 LAST SIG_NAME KR_P0_OCP_TX_DP
J 0
(-2950 2110);
DISPLAY 0.617021 (-2950 2110);
PAINT ORANGE (-2950 2110);
WIRE 16 -1 (-3000 2125)(-3000 2100);
WIRE 16 -1 (-3125 2125)(-3000 2125);
WIRE 16 -1 (-4325 1075)(-3700 1075);
FORCEPROP 0 LAST SIG_NAME XDP_CPU_PWR_DEBUG_N
J 0
(-4260 1085);
DISPLAY 0.617021 (-4260 1085);
PAINT ORANGE (-4260 1085);
WIRE 16 -1 (-1575 675)(-875 675);
FORCEPROP 2 LAST SIG_NAME FM_10GBE_LOM_DISABLE_N
J 0
(-1385 685);
DISPLAY 0.617021 (-1385 685);
PAINT ORANGE (-1385 685);
WIRE 16 -1 (-1575 900)(-875 900);
FORCEPROP 2 LAST SIG_NAME FM_1GB_LOM_DISABLE_N
J 0
(-1385 910);
DISPLAY 0.617021 (-1385 910);
PAINT ORANGE (-1385 910);
WIRE 16 -1 (-3125 1725)(-2575 1725);
FORCEPROP 2 LAST SIG_NAME TP_PCH_RSVD41
J 0
(-2975 1735);
DISPLAY 0.617021 (-2975 1735);
PAINT ORANGE (-2975 1735);
FORCEPROP 2 LASTPROP $XRERR UNIQUE?
J 0
(-2545 1725);
DISPLAY 0.638298 (-2545 1725);
PAINT MONO (-2545 1725);
DISPLAY INVISIBLE (-2545 1725);
WIRE 16 -1 (-3125 1775)(-2575 1775);
FORCEPROP 2 LAST SIG_NAME TP_PCH_RSVD42
J 0
(-2975 1785);
DISPLAY 0.617021 (-2975 1785);
PAINT ORANGE (-2975 1785);
FORCEPROP 2 LASTPROP $XRERR UNIQUE?
J 0
(-2545 1775);
DISPLAY 0.638298 (-2545 1775);
PAINT MONO (-2545 1775);
DISPLAY INVISIBLE (-2545 1775);
WIRE 16 -1 (-3125 1975)(-2350 1975);
FORCEPROP 2 LAST SIG_NAME TP_10GBE_KR1_MON_DP
J 0
(-2975 1985);
DISPLAY 0.617021 (-2975 1985);
PAINT ORANGE (-2975 1985);
FORCEPROP 2 LASTPROP $XRERR UNIQUE?
J 0
(-2320 1975);
DISPLAY 0.638298 (-2320 1975);
PAINT MONO (-2320 1975);
DISPLAY INVISIBLE (-2320 1975);
WIRE 16 -1 (-5625 2875)(-4925 2875);
FORCEPROP 2 LAST SIG_NAME XDP_PREQ_N
J 0
(-5625 2885);
DISPLAY 0.617021 (-5625 2885);
PAINT ORANGE (-5625 2885);
WIRE 16 -1 (-3125 1925)(-2350 1925);
FORCEPROP 2 LAST SIG_NAME TP_10GBE_KR1_MON_DN
J 0
(-2975 1935);
DISPLAY 0.617021 (-2975 1935);
PAINT ORANGE (-2975 1935);
FORCEPROP 2 LASTPROP $XRERR UNIQUE?
J 0
(-2320 1925);
DISPLAY 0.638298 (-2320 1925);
PAINT MONO (-2320 1925);
DISPLAY INVISIBLE (-2320 1925);
WIRE 16 -1 (-1975 4025)(-3125 4025);
FORCEPROP 2 LAST SIG_NAME RST_RSMRST_N
J 0
(-2935 4035);
DISPLAY 0.617021 (-2935 4035);
PAINT ORANGE (-2935 4035);
WIRE 16 -1 (-2375 3925)(-3125 3925);
FORCEPROP 2 LAST SIG_NAME TP_PLTRST_CPU_N
J 0
(-2935 3935);
DISPLAY 0.617021 (-2935 3935);
PAINT ORANGE (-2935 3935);
FORCEPROP 2 LASTPROP $XRERR UNIQUE?
J 0
(-2345 3925);
DISPLAY 0.638298 (-2345 3925);
PAINT MONO (-2345 3925);
DISPLAY INVISIBLE (-2345 3925);
WIRE 16 -1 (-3000 3650)(-2825 3650);
WIRE 16 -1 (-3000 3875)(-3125 3875);
WIRE 16 -1 (-3000 3875)(-3000 3650);
WIRE 16 -1 (-1975 3875)(-3000 3875);
FORCEPROP 2 LAST SIG_NAME RST_BMC_SYSRST_BTN_OUT_B_N
J 0
(-2935 3885);
DISPLAY 0.617021 (-2935 3885);
PAINT ORANGE (-2935 3885);
WIRE 16 -1 (-1975 4075)(-3125 4075);
FORCEPROP 2 LAST SIG_NAME TP_SLP_LAN_N
J 0
(-2935 4085);
DISPLAY 0.617021 (-2935 4085);
PAINT ORANGE (-2935 4085);
FORCEPROP 2 LASTPROP $XRERR UNIQUE?
J 0
(-1945 4075);
DISPLAY 0.638298 (-1945 4075);
PAINT MONO (-1945 4075);
DISPLAY INVISIBLE (-1945 4075);
WIRE 16 -1 (-1975 4125)(-3125 4125);
FORCEPROP 2 LAST SIG_NAME FM_SLP_SUS_N
J 0
(-2935 4135);
DISPLAY 0.617021 (-2935 4135);
PAINT ORANGE (-2935 4135);
WIRE 16 -1 (-3125 4275)(-1975 4275);
FORCEPROP 2 LAST SIG_NAME PWRGD_SYS_PWROK
J 0
(-2935 4285);
DISPLAY 0.617021 (-2935 4285);
PAINT ORANGE (-2935 4285);
WIRE 16 -1 (-3125 4325)(-1975 4325);
FORCEPROP 2 LAST SIG_NAME PWRGD_PCH_PWROK
J 0
(-2935 4335);
DISPLAY 0.617021 (-2935 4335);
PAINT ORANGE (-2935 4335);
WIRE 16 -1 (-2300 4175)(-3125 4175);
FORCEPROP 2 LAST SIG_NAME IRQ_LVC3_WAKE_N
J 0
(-2935 4185);
DISPLAY 0.617021 (-2935 4185);
PAINT ORANGE (-2935 4185);
WIRE 16 -1 (-2300 4550)(-2300 4175);
WIRE 16 -1 (-1975 4175)(-2300 4175);
WIRE 16 -1 (-3125 4375)(-1975 4375);
FORCEPROP 2 LAST SIG_NAME PWRGD_DSW_PWROK
J 0
(-2935 4385);
DISPLAY 0.617021 (-2935 4385);
PAINT ORANGE (-2935 4385);
WIRE 16 -1 (-3125 4425)(-1975 4425);
FORCEPROP 2 LAST SIG_NAME PWRGD_CPUPWRGD_GTL
J 0
(-2935 4435);
DISPLAY 0.617021 (-2935 4435);
PAINT ORANGE (-2935 4435);
WIRE 16 -1 (-5600 1975)(-4925 1975);
FORCEPROP 2 LAST SIG_NAME TP_10GBE_KR0_MON_DP
J 0
(-5550 1985);
DISPLAY 0.617021 (-5550 1985);
PAINT ORANGE (-5550 1985);
FORCEPROP 2 LASTPROP $XRERR UNIQUE?
J 0
(-5840 1975);
DISPLAY 0.638298 (-5840 1975);
PAINT MONO (-5840 1975);
DISPLAY INVISIBLE (-5840 1975);
WIRE 16 -1 (-5600 1775)(-4925 1775);
FORCEPROP 2 LAST SIG_NAME TP_PCH_RSVD38
J 0
(-5550 1785);
DISPLAY 0.617021 (-5550 1785);
PAINT ORANGE (-5550 1785);
FORCEPROP 2 LASTPROP $XRERR UNIQUE?
J 0
(-5840 1775);
DISPLAY 0.638298 (-5840 1775);
PAINT MONO (-5840 1775);
DISPLAY INVISIBLE (-5840 1775);
WIRE 16 -1 (-4925 1625)(-5625 1625);
FORCEPROP 2 LAST SIG_NAME XTAL_KR_25M_IN
J 0
(-5625 1635);
DISPLAY 0.617021 (-5625 1635);
PAINT ORANGE (-5625 1635);
WIRE 16 -1 (-5600 1925)(-4925 1925);
FORCEPROP 2 LAST SIG_NAME TP_10GBE_KR0_MON_DN
J 0
(-5550 1935);
DISPLAY 0.617021 (-5550 1935);
PAINT ORANGE (-5550 1935);
FORCEPROP 2 LASTPROP $XRERR UNIQUE?
J 0
(-5840 1925);
DISPLAY 0.638298 (-5840 1925);
PAINT MONO (-5840 1925);
DISPLAY INVISIBLE (-5840 1925);
WIRE 16 -1 (-5650 2975)(-4925 2975);
FORCEPROP 2 LAST SIG_NAME XDP_PCH_CPU_TCK0
J 0
(-5625 2985);
DISPLAY 0.617021 (-5625 2985);
PAINT ORANGE (-5625 2985);
WIRE 16 -1 (-5625 3125)(-4925 3125);
FORCEPROP 2 LAST SIG_NAME XDP_TDI
J 0
(-5625 3135);
DISPLAY 0.617021 (-5625 3135);
PAINT ORANGE (-5625 3135);
WIRE 16 -1 (-5625 3075)(-4925 3075);
FORCEPROP 2 LAST SIG_NAME XDP_TDO
J 0
(-5625 3085);
DISPLAY 0.617021 (-5625 3085);
PAINT ORANGE (-5625 3085);
WIRE 16 -1 (-5625 3025)(-4925 3025);
FORCEPROP 2 LAST SIG_NAME XDP_TMS
J 0
(-5625 3035);
DISPLAY 0.617021 (-5625 3035);
PAINT ORANGE (-5625 3035);
WIRE 16 -1 (-7325 3975)(-6725 3975);
FORCEPROP 0 LAST SIG_NAME RST_BMC_SRST_N
J 0
(-7310 3985);
DISPLAY 0.617021 (-7310 3985);
PAINT ORANGE (-7310 3985);
WIRE 16 -1 (-7325 4225)(-6750 4225);
FORCEPROP 2 LAST SIG_NAME FM_BATTERY_SENSE_EN_N
J 0
(-7325 4235);
DISPLAY 0.617021 (-7325 4235);
PAINT ORANGE (-7325 4235);
WIRE 16 -1 (-5600 2175)(-4925 2175);
FORCEPROP 0 LAST SIG_NAME KR_P1_OCP_RX_C_DN
J 0
(-5575 2185);
DISPLAY 0.617021 (-5575 2185);
PAINT ORANGE (-5575 2185);
WIRE 16 -1 (-7700 1150)(-7175 1150);
WIRE 16 -1 (-7700 700)(-7700 850);
WIRE 16 -1 (-7700 850)(-7500 850);
WIRE 16 -1 (-7700 850)(-7700 1150);
FORCEPROP 2 LAST SIG_NAME XTAL_KR_25M_IN
J 0
(-7710 1160);
DISPLAY 0.617021 (-7710 1160);
PAINT ORANGE (-7710 1160);
WIRE 16 -1 (-7250 850)(-7300 850);
WIRE 16 -1 (-7250 850)(-6800 850);
FORCEPROP 2 LAST SIG_NAME XTAL_KR_25M_OUT
J 0
(-7160 860);
DISPLAY 0.617021 (-7160 860);
PAINT ORANGE (-7160 860);
WIRE 16 -1 (-7250 700)(-7250 850);
WIRE 3 682 (-7800 350)(-7800 750);
WIRE 3 682 (-6950 350)(-7800 350);
WIRE 3 682 (-6950 750)(-7800 750);
WIRE 3 682 (-6950 750)(-6950 350);
WIRE 16 -1 (-5625 3175)(-4925 3175);
FORCEPROP 2 LAST SIG_NAME XDP_PCH_TCK1
J 0
(-5625 3185);
DISPLAY 0.617021 (-5625 3185);
PAINT ORANGE (-5625 3185);
WIRE 16 -1 (-5575 3275)(-4925 3275);
FORCEPROP 2 LAST SIG_NAME TP_CPU_PCH_TRIGGER_OUT
J 0
(-5550 3285);
DISPLAY 0.617021 (-5550 3285);
PAINT ORANGE (-5550 3285);
FORCEPROP 2 LASTPROP $XRERR UNIQUE?
J 0
(-5815 3275);
DISPLAY 0.638298 (-5815 3275);
PAINT MONO (-5815 3275);
DISPLAY INVISIBLE (-5815 3275);
WIRE 16 -1 (-5575 3325)(-4925 3325);
FORCEPROP 2 LAST SIG_NAME TP_CPU_PCH_TRIGGER_IN
J 0
(-5550 3335);
DISPLAY 0.617021 (-5550 3335);
PAINT ORANGE (-5550 3335);
FORCEPROP 2 LASTPROP $XRERR UNIQUE?
J 0
(-5815 3325);
DISPLAY 0.638298 (-5815 3325);
PAINT MONO (-5815 3325);
DISPLAY INVISIBLE (-5815 3325);
WIRE 16 -1 (-7325 4375)(-6750 4375);
FORCEPROP 0 LAST SIG_NAME FM_CPU0_RC_ERROR_N
J 0
(-7325 4386);
DISPLAY 0.617021 (-7325 4386);
PAINT ORANGE (-7325 4386);
WIRE 16 -1 (-4925 4275)(-5725 4275);
FORCEPROP 2 LAST SIG_NAME TP_PCH_GDP8_SUSCLK
J 0
(-5725 4285);
DISPLAY 0.617021 (-5725 4285);
PAINT ORANGE (-5725 4285);
FORCEPROP 2 LASTPROP $XRERR UNIQUE?
J 0
(-5965 4275);
DISPLAY 0.638298 (-5965 4275);
PAINT MONO (-5965 4275);
DISPLAY INVISIBLE (-5965 4275);
WIRE 16 -1 (-5725 4325)(-4925 4325);
FORCEPROP 2 LAST SIG_NAME FM_BMC_CPLD_MP_RST_N
J 0
(-5725 4335);
DISPLAY 0.617021 (-5725 4335);
PAINT ORANGE (-5725 4335);
WIRE 16 -1 (-1925 675)(-1775 675);
WIRE 16 -1 (-2200 900)(-2850 900);
FORCEPROP 2 LAST SIG_NAME FM_GBE_LOM_DISABLE_N
J 0
(-2810 910);
DISPLAY 0.617021 (-2810 910);
PAINT ORANGE (-2810 910);
WIRE 16 -1 (-2200 900)(-2200 1000);
WIRE 16 -1 (-1925 900)(-2200 900);
WIRE 16 -1 (-1925 900)(-1925 675);
WIRE 16 -1 (-1775 900)(-1925 900);
WIRE 16 -1 (-4825 1025)(-5750 1025);
FORCEPROP 0 LAST SIG_NAME PWRGD_PVCCIO_CPU0
J 0
(-5710 1035);
DISPLAY 0.617021 (-5710 1035);
PAINT ORANGE (-5710 1035);
WIRE 16 -1 (-5750 1075)(-5175 1075);
FORCEPROP 0 LAST SIG_NAME XDP_PCH_PWR_DEBUG_N
J 0
(-5710 1085);
DISPLAY 0.617021 (-5710 1085);
PAINT ORANGE (-5710 1085);
WIRE 16 -1 (-4825 1075)(-5175 1075);
WIRE 16 -1 (-5175 1175)(-5175 1075);
WIRE 16 -1 (-5600 1725)(-4925 1725);
FORCEPROP 2 LAST SIG_NAME TP_PCH_RSVD37
J 0
(-5550 1735);
DISPLAY 0.617021 (-5550 1735);
PAINT ORANGE (-5550 1735);
FORCEPROP 2 LASTPROP $XRERR UNIQUE?
J 0
(-5840 1725);
DISPLAY 0.638298 (-5840 1725);
PAINT MONO (-5840 1725);
DISPLAY INVISIBLE (-5840 1725);
WIRE 16 -1 (-4925 1875)(-7225 1875);
FORCEPROP 0 LAST SIG_NAME A_KR0_RBIAS
J 0
(-6175 1875);
DISPLAY 0.617021 (-6175 1875);
PAINT ORANGE (-6175 1875);
FORCEPROP 2 LASTPROP $XRERR UNIQUE?
J 0
(-6415 1875);
DISPLAY 0.638298 (-6415 1875);
PAINT MONO (-6415 1875);
DISPLAY INVISIBLE (-6415 1875);
WIRE 16 -1 (-7225 2075)(-7225 1875);
WIRE 16 -1 (-5150 2075)(-4925 2075);
WIRE 16 -1 (-5600 2050)(-5150 2050);
FORCEPROP 0 LAST SIG_NAME KR_P0_OCP_RX_C_DN
J 0
(-5575 2060);
DISPLAY 0.617021 (-5575 2060);
PAINT ORANGE (-5575 2060);
WIRE 16 -1 (-5150 2050)(-5150 2075);
WIRE 3 2175 (-5825 2550)(-5075 2550);
WIRE 3 2175 (-5075 2550)(-5075 2150);
WIRE 3 2175 (-5825 2550)(-5825 2150);
WIRE 3 2175 (-5825 2150)(-5075 2150);
WIRE 16 -1 (-5625 2675)(-4925 2675);
FORCEPROP 2 LAST SIG_NAME XDP_TRST_N
J 0
(-5625 2685);
DISPLAY 0.617021 (-5625 2685);
PAINT ORANGE (-5625 2685);
WIRE 16 -1 (-7325 4075)(-6750 4075);
FORCEPROP 2 LAST SIG_NAME FM_SLPS3_N
J 0
(-7325 4085);
DISPLAY 0.617021 (-7325 4085);
PAINT ORANGE (-7325 4085);
DOT 1 (-5175 1075);
DOT 1 (-3000 3875);
DOT 1 (-7250 850);
DOT 1 (-2200 900);
DOT 1 (-1925 900);
DOT 1 (-1075 2675);
DOT 1 (-2300 4175);
DOT 1 (-7700 850);
DOT 1 (-6450 4225);
DOT 1 (-6200 3975);
DOT 1 (-6450 4800);
FORCENOTE
TP FAB1 PUT KR1 BACK 0322
(-6675 2250) 0;
DISPLAY LEFT (-6675 2250);
DISPLAY 0.808511 (-6675 2250);
PAINT RED (-6675 2250);
FORCENOTE
TP FAB1 ADD RES 0226
(-2625 3550) 0;
DISPLAY LEFT (-2625 3550);
DISPLAY 1.021277 (-2625 3550);
PAINT RED (-2625 3550);
FORCENOTE
BOM_COST=SB
(-6775 125) 0;
DISPLAY LEFT (-6775 125);
DISPLAY 1.021277 (-6775 125);
PAINT PURPLE (-6775 125);
FORCENOTE
ROOM-SB
(-6775 175) 0;
DISPLAY LEFT (-6775 175);
DISPLAY 1.021277 (-6775 175);
PAINT PURPLE (-6775 175);
FORCENOTE
TP FAB3 CHANGE CAPS TO 15PF 0815
(-7800 300) 0;
DISPLAY LEFT (-7800 300);
DISPLAY 0.638298 (-7800 300);
PAINT RED (-7800 300);
FORCENOTE
TP FAB3 CHANGE CAPS TO 33PF 20161221
(-7800 250) 0;
DISPLAY LEFT (-7800 250);
DISPLAY 0.638298 (-7800 250);
PAINT RED (-7800 250);
FORCENOTE
TP FAB1 DELETE CONNECTION TO MEZZC 0106
(-6125 2575) 0;
DISPLAY LEFT (-6125 2575);
DISPLAY 0.808511 (-6125 2575);
PAINT RED (-6125 2575);
FORCENOTE
TP FAB4 NOPOP R7D23 20170207
(-6750 3775) 0;
DISPLAY LEFT (-6750 3775);
DISPLAY 0.638298 (-6750 3775);
PAINT RED (-6750 3775);
FORCENOTE
TP FAB1 ADD RES R7W1 0114
(-6525 4075) 0;
DISPLAY LEFT (-6525 4075);
DISPLAY 0.638298 (-6525 4075);
PAINT RED (-6525 4075);
FORCENOTE
TP FAB3-DVT ADD RES R7W6 20161128
(-6525 4225) 0;
DISPLAY LEFT (-6525 4225);
DISPLAY 0.638298 (-6525 4225);
PAINT RED (-6525 4225);
FORCENOTE
TP FAB4 ADD R7W21 20170207
(-6000 4625) 0;
DISPLAY LEFT (-6000 4625);
DISPLAY 0.638298 (-6000 4625);
PAINT RED (-6000 4625);
FORCENOTE
TP FAB4 ADD R7W19 20170116
(-6000 4675) 0;
DISPLAY LEFT (-6000 4675);
DISPLAY 0.638298 (-6000 4675);
PAINT RED (-6000 4675);
FORCENOTE
TP FAB3-DVT CHANGE CONNECTION 20161117
(-5500 4775) 0;
DISPLAY LEFT (-5500 4775);
DISPLAY 0.638298 (-5500 4775);
PAINT RED (-5500 4775);
FORCENOTE
TP FAB1 PUT KR1 BACK 0322
(-2200 2150) 0;
DISPLAY LEFT (-2200 2150);
DISPLAY 0.808511 (-2200 2150);
PAINT RED (-2200 2150);
FORCENOTE
TP FAB1 DELETE CONNECTION TO MEZZ C 1230
(-3025 2550) 0;
DISPLAY LEFT (-3025 2550);
DISPLAY 0.808511 (-3025 2550);
PAINT RED (-3025 2550);
FORCENOTE
TP FAB3-DVT ADD RES R7W9 20161201
(-6525 4375) 0;
DISPLAY LEFT (-6525 4375);
DISPLAY 0.638298 (-6525 4375);
PAINT RED (-6525 4375);
QUIT
